G04 ================== begin FILE IDENTIFICATION RECORD ==================*
G04 Layout Name:  15126-1b.brd*
G04 Film Name:    BSMD*
G04 File Format:  Gerber RS274X*
G04 File Origin:  Cadence Allegro 16.6-2015-S079*
G04 Origin Date:  Fri Feb 10 17:21:50 2017*
G04 *
G04 Layer:  PIN/PASTEMASK_BOTTOM*
G04 Layer:  PACKAGE GEOMETRY/PASTEMASK_BOTTOM*
G04 Layer:  DRAWING FORMAT/LAYER_PAST_B*
G04 Layer:  VIA CLASS/PASTEMASK_BOTTOM*
G04 Layer:  DRAWING FORMAT/LAYER_PCB_STORY*
G04 Layer:  BOARD GEOMETRY/PANEL_OUTLINE*
G04 *
G04 Offset:    (0.00 0.00)*
G04 Mirror:    No*
G04 Mode:      Positive*
G04 Rotation:  0*
G04 FullContactRelief:  No*
G04 UndefLineWidth:     6.00*
G04 ================== end FILE IDENTIFICATION RECORD ====================*
%FSLAX35Y35*MOIN*%
%IR0*IPPOS*OFA0.00000B0.00000*MIA0B0*SFA1.00000B1.00000*%
%AMMACRO102*
4,1,40,.011,.007,
.011,-.007,
.010939,-.007695,
.010759,-.008368,
.010464,-.009,
.010064,-.009571,
.009571,-.010064,
.009,-.010464,
.008368,-.010759,
.007695,-.010939,
.007,-.011,
-.007,-.011,
-.007695,-.010939,
-.008368,-.010759,
-.009,-.010464,
-.009571,-.010064,
-.010064,-.009571,
-.010464,-.009,
-.010759,-.008368,
-.010939,-.007695,
-.011,-.007,
-.011,.007,
-.010939,.007695,
-.010759,.008368,
-.010464,.009,
-.010064,.009571,
-.009571,.010064,
-.009,.010464,
-.008368,.010759,
-.007695,.010939,
-.007,.011,
.007,.011,
.007695,.010939,
.008368,.010759,
.009,.010464,
.009571,.010064,
.010064,.009571,
.010464,.009,
.010759,.008368,
.010939,.007695,
.011,.007,
0.0*
%
%ADD102MACRO102*%
%AMMACRO131*
4,1,40,-.017,-.013,
-.017,.013,
-.016939,.013695,
-.016759,.014368,
-.016464,.015,
-.016064,.015571,
-.015571,.016064,
-.015,.016464,
-.014368,.016759,
-.013695,.016939,
-.013,.017,
.013,.017,
.013695,.016939,
.014368,.016759,
.015,.016464,
.015571,.016064,
.016064,.015571,
.016464,.015,
.016759,.014368,
.016939,.013695,
.017,.013,
.017,-.013,
.016939,-.013695,
.016759,-.014368,
.016464,-.015,
.016064,-.015571,
.015571,-.016064,
.015,-.016464,
.014368,-.016759,
.013695,-.016939,
.013,-.017,
-.013,-.017,
-.013695,-.016939,
-.014368,-.016759,
-.015,-.016464,
-.015571,-.016064,
-.016064,-.015571,
-.016464,-.015,
-.016759,-.014368,
-.016939,-.013695,
-.017,-.013,
0.0*
%
%ADD131MACRO131*%
%AMMACRO127*
4,1,40,.013,-.017,
-.013,-.017,
-.013695,-.016939,
-.014368,-.016759,
-.015,-.016464,
-.015571,-.016064,
-.016064,-.015571,
-.016464,-.015,
-.016759,-.014368,
-.016939,-.013695,
-.017,-.013,
-.017,.013,
-.016939,.013695,
-.016759,.014368,
-.016464,.015,
-.016064,.015571,
-.015571,.016064,
-.015,.016464,
-.014368,.016759,
-.013695,.016939,
-.013,.017,
.013,.017,
.013695,.016939,
.014368,.016759,
.015,.016464,
.015571,.016064,
.016064,.015571,
.016464,.015,
.016759,.014368,
.016939,.013695,
.017,.013,
.017,-.013,
.016939,-.013695,
.016759,-.014368,
.016464,-.015,
.016064,-.015571,
.015571,-.016064,
.015,-.016464,
.014368,-.016759,
.013695,-.016939,
.013,-.017,
0.0*
%
%ADD127MACRO127*%
%AMMACRO116*
4,1,40,.0105,.015,
-.0105,.015,
-.011195,.014939,
-.011868,.014759,
-.0125,.014464,
-.013071,.014064,
-.013564,.013571,
-.013964,.013,
-.014259,.012368,
-.014439,.011695,
-.0145,.011,
-.0145,-.011,
-.014439,-.011695,
-.014259,-.012368,
-.013964,-.013,
-.013564,-.013571,
-.013071,-.014064,
-.0125,-.014464,
-.011868,-.014759,
-.011195,-.014939,
-.0105,-.015,
.0105,-.015,
.011195,-.014939,
.011868,-.014759,
.0125,-.014464,
.013071,-.014064,
.013564,-.013571,
.013964,-.013,
.014259,-.012368,
.014439,-.011695,
.0145,-.011,
.0145,.011,
.014439,.011695,
.014259,.012368,
.013964,.013,
.013564,.013571,
.013071,.014064,
.0125,.014464,
.011868,.014759,
.011195,.014939,
.0105,.015,
0.0*
%
%ADD116MACRO116*%
%ADD55O,.062X.111*%
%AMMACRO108*
21,1,.004,.02,0.0,0.0,11.32*%
%ADD108MACRO108*%
%ADD54R,.02X.004*%
%AMMACRO36*
4,1,8,.0825,.065,
.0825,-.065,
-.0175,-.065,
-.0175,-.087,
-.0825,-.087,
-.0825,.087,
-.0175,.087,
-.0175,.065,
.0825,.065,
0.0*
%
%ADD36MACRO36*%
%AMMACRO72*
4,1,4,.00216,-.0111,
-.0111,-.00216,
-.00216,.0111,
.0111,.00216,
.00216,-.0111,
0.0*
%
%ADD72MACRO72*%
%ADD68R,.004X.02*%
%AMMACRO73*
4,1,4,.00235,-.01106,
-.01106,-.00235,
-.00235,.01106,
.01106,.00235,
.00235,-.01106,
0.0*
%
%ADD73MACRO73*%
%AMMACRO24*
4,1,12,-.0195,-.0325,
-.0195,.0325,
.0195,.0325,
.0195,.0195,
-.0005,.0195,
-.0005,.0065,
.0195,.0065,
.0195,-.0065,
-.0005,-.0065,
-.0005,-.0195,
.0195,-.0195,
.0195,-.0325,
-.0195,-.0325,
0.0*
%
%ADD24MACRO24*%
%ADD23R,.134X.024*%
%ADD12R,.053X.106*%
%AMMACRO117*
4,1,4,.00312,-.01087,
-.01087,-.00312,
-.00312,.01087,
.01087,.00312,
.00312,-.01087,
0.0*
%
%ADD117MACRO117*%
%AMMACRO71*
4,1,4,.00225,-.01108,
-.01108,-.00225,
-.00225,.01108,
.01108,.00225,
.00225,-.01108,
0.0*
%
%ADD71MACRO71*%
%ADD168R,.008X.014*%
%ADD15C,.04*%
%ADD159R,.014X.008*%
%AMMACRO109*
4,1,4,.00433,-.01045,
-.01045,-.00433,
-.00433,.01045,
.01045,.00433,
.00433,-.01045,
0.0*
%
%ADD109MACRO109*%
%AMMACRO47*
4,1,4,.01131,0.0,
0.0,-.01131,
-.01131,0.0,
0.0,.01131,
.01131,0.0,
0.0*
%
%ADD47MACRO47*%
%AMMACRO37*
4,1,4,.008,-.008,
-.008,-.008,
-.008,.008,
.008,.008,
.008,-.008,
0.0*
%
%ADD37MACRO37*%
%AMMACRO33*
4,1,4,0.0,-.01131,
-.01131,0.0,
0.0,.01131,
.01131,0.0,
0.0,-.01131,
0.0*
%
%ADD33MACRO33*%
%ADD22R,.134X.047*%
%ADD99C,.026*%
%ADD14C,.086*%
%AMMACRO62*
4,1,4,.01108,-.00229,
-.00229,-.01108,
-.01108,.00229,
.00229,.01108,
.01108,-.00229,
0.0*
%
%ADD62MACRO62*%
%ADD110R,.037X.037*%
%AMMACRO67*
4,1,4,.0111,-.00215,
-.00215,-.0111,
-.0111,.00215,
.00215,.0111,
.0111,-.00215,
0.0*
%
%ADD67MACRO67*%
%AMMACRO143*
4,1,40,-.011,-.007,
-.011,.007,
-.010939,.007695,
-.010759,.008368,
-.010464,.009,
-.010064,.009571,
-.009571,.010064,
-.009,.010464,
-.008368,.010759,
-.007695,.010939,
-.007,.011,
.007,.011,
.007695,.010939,
.008368,.010759,
.009,.010464,
.009571,.010064,
.010064,.009571,
.010464,.009,
.010759,.008368,
.010939,.007695,
.011,.007,
.011,-.007,
.010939,-.007695,
.010759,-.008368,
.010464,-.009,
.010064,-.009571,
.009571,-.010064,
.009,-.010464,
.008368,-.010759,
.007695,-.010939,
.007,-.011,
-.007,-.011,
-.007695,-.010939,
-.008368,-.010759,
-.009,-.010464,
-.009571,-.010064,
-.010064,-.009571,
-.010464,-.009,
-.010759,-.008368,
-.010939,-.007695,
-.011,-.007,
0.0*
%
%ADD143MACRO143*%
%AMMACRO100*
4,1,4,.00013,-.01131,
-.01131,-.00013,
-.00013,.01131,
.01131,.00013,
.00013,-.01131,
0.0*
%
%ADD100MACRO100*%
%AMMACRO45*
4,1,40,.007,-.011,
-.007,-.011,
-.007695,-.010939,
-.008368,-.010759,
-.009,-.010464,
-.009571,-.010064,
-.010064,-.009571,
-.010464,-.009,
-.010759,-.008368,
-.010939,-.007695,
-.011,-.007,
-.011,.007,
-.010939,.007695,
-.010759,.008368,
-.010464,.009,
-.010064,.009571,
-.009571,.010064,
-.009,.010464,
-.008368,.010759,
-.007695,.010939,
-.007,.011,
.007,.011,
.007695,.010939,
.008368,.010759,
.009,.010464,
.009571,.010064,
.010064,.009571,
.010464,.009,
.010759,.008368,
.010939,.007695,
.011,.007,
.011,-.007,
.010939,-.007695,
.010759,-.008368,
.010464,-.009,
.010064,-.009571,
.009571,-.010064,
.009,-.010464,
.008368,-.010759,
.007695,-.010939,
.007,-.011,
0.0*
%
%ADD45MACRO45*%
%AMMACRO86*
4,1,4,.0113,-.00037,
-.00037,-.0113,
-.0113,.00037,
.00037,.0113,
.0113,-.00037,
0.0*
%
%ADD86MACRO86*%
%AMMACRO84*
4,1,4,.01131,-.00029,
-.00029,-.01131,
-.01131,.00029,
.00029,.01131,
.01131,-.00029,
0.0*
%
%ADD84MACRO84*%
%AMMACRO81*
4,1,4,.011,-.00261,
-.00261,-.011,
-.011,.00261,
.00261,.011,
.011,-.00261,
0.0*
%
%ADD81MACRO81*%
%AMMACRO75*
4,1,4,.00875,-.00717,
-.00717,-.00875,
-.00875,.00717,
.00717,.00875,
.00875,-.00717,
0.0*
%
%ADD75MACRO75*%
%AMMACRO74*
4,1,4,.01095,-.00283,
-.00283,-.01095,
-.01095,.00283,
.00283,.01095,
.01095,-.00283,
0.0*
%
%ADD74MACRO74*%
%AMMACRO138*
4,1,4,.00809,-.00791,
-.00791,-.00809,
-.00809,.00791,
.00791,.00809,
.00809,-.00791,
0.0*
%
%ADD138MACRO138*%
%AMMACRO85*
4,1,4,.0113,-.00035,
-.00035,-.0113,
-.0113,.00035,
.00035,.0113,
.0113,-.00035,
0.0*
%
%ADD85MACRO85*%
%AMMACRO88*
4,1,4,.0113,-.00043,
-.00043,-.0113,
-.0113,.00043,
.00043,.0113,
.0113,-.00043,
0.0*
%
%ADD88MACRO88*%
%AMMACRO19*
4,1,40,-.012,-.008,
-.012,.008,
-.011939,.008695,
-.011759,.009368,
-.011464,.01,
-.011064,.010571,
-.010571,.011064,
-.01,.011464,
-.009368,.011759,
-.008695,.011939,
-.008,.012,
.008,.012,
.008695,.011939,
.009368,.011759,
.01,.011464,
.010571,.011064,
.011064,.010571,
.011464,.01,
.011759,.009368,
.011939,.008695,
.012,.008,
.012,-.008,
.011939,-.008695,
.011759,-.009368,
.011464,-.01,
.011064,-.010571,
.010571,-.011064,
.01,-.011464,
.009368,-.011759,
.008695,-.011939,
.008,-.012,
-.008,-.012,
-.008695,-.011939,
-.009368,-.011759,
-.01,-.011464,
-.010571,-.011064,
-.011064,-.010571,
-.011464,-.01,
-.011759,-.009368,
-.011939,-.008695,
-.012,-.008,
0.0*
%
%ADD19MACRO19*%
%AMMACRO105*
4,1,8,.0034,.0082,
-.0034,.0082,
-.0082,.0034,
-.0082,-.00341,
-.00341,-.0082,
.0034,-.0082,
.0082,-.0034,
.0082,.0034,
.0034,.0082,
0.0*
%
%ADD105MACRO105*%
%AMMACRO87*
4,1,4,.01131,-.00026,
-.00026,-.01131,
-.01131,.00026,
.00026,.01131,
.01131,-.00026,
0.0*
%
%ADD87MACRO87*%
%AMMACRO63*
4,1,4,.01108,-.00229,
-.00229,-.01108,
-.01108,.00229,
.00229,.01108,
.01108,-.00229,
0.0*
%
%ADD63MACRO63*%
%AMMACRO61*
4,1,4,.01109,-.0022,
-.0022,-.01109,
-.01109,.0022,
.0022,.01109,
.01109,-.0022,
0.0*
%
%ADD61MACRO61*%
%AMMACRO48*
4,1,40,-.008,.012,
.008,.012,
.008695,.011939,
.009368,.011759,
.01,.011464,
.010571,.011064,
.011064,.010571,
.011464,.01,
.011759,.009368,
.011939,.008695,
.012,.008,
.012,-.008,
.011939,-.008695,
.011759,-.009368,
.011464,-.01,
.011064,-.010571,
.010571,-.011064,
.01,-.011464,
.009368,-.011759,
.008695,-.011939,
.008,-.012,
-.008,-.012,
-.008695,-.011939,
-.009368,-.011759,
-.01,-.011464,
-.010571,-.011064,
-.011064,-.010571,
-.011464,-.01,
-.011759,-.009368,
-.011939,-.008695,
-.012,-.008,
-.012,.008,
-.011939,.008695,
-.011759,.009368,
-.011464,.01,
-.011064,.010571,
-.010571,.011064,
-.01,.011464,
-.009368,.011759,
-.008695,.011939,
-.008,.012,
0.0*
%
%ADD48MACRO48*%
%AMMACRO124*
4,1,40,-.013,.017,
.013,.017,
.013695,.016939,
.014368,.016759,
.015,.016464,
.015571,.016064,
.016064,.015571,
.016464,.015,
.016759,.014368,
.016939,.013695,
.017,.013,
.017,-.013,
.016939,-.013695,
.016759,-.014368,
.016464,-.015,
.016064,-.015571,
.015571,-.016064,
.015,-.016464,
.014368,-.016759,
.013695,-.016939,
.013,-.017,
-.013,-.017,
-.013695,-.016939,
-.014368,-.016759,
-.015,-.016464,
-.015571,-.016064,
-.016064,-.015571,
-.016464,-.015,
-.016759,-.014368,
-.016939,-.013695,
-.017,-.013,
-.017,.013,
-.016939,.013695,
-.016759,.014368,
-.016464,.015,
-.016064,.015571,
-.015571,.016064,
-.015,.016464,
-.014368,.016759,
-.013695,.016939,
-.013,.017,
0.0*
%
%ADD124MACRO124*%
%AMMACRO107*
4,1,8,.0082,-.0034,
.0082,.0034,
.0034,.0082,
-.00341,.0082,
-.0082,.00341,
-.0082,-.0034,
-.0034,-.0082,
.0034,-.0082,
.0082,-.0034,
0.0*
%
%ADD107MACRO107*%
%AMMACRO82*
4,1,4,.01131,-.00023,
-.00023,-.01131,
-.01131,.00023,
.00023,.01131,
.01131,-.00023,
0.0*
%
%ADD82MACRO82*%
%AMMACRO128*
4,1,40,.017,.013,
.017,-.013,
.016939,-.013695,
.016759,-.014368,
.016464,-.015,
.016064,-.015571,
.015571,-.016064,
.015,-.016464,
.014368,-.016759,
.013695,-.016939,
.013,-.017,
-.013,-.017,
-.013695,-.016939,
-.014368,-.016759,
-.015,-.016464,
-.015571,-.016064,
-.016064,-.015571,
-.016464,-.015,
-.016759,-.014368,
-.016939,-.013695,
-.017,-.013,
-.017,.013,
-.016939,.013695,
-.016759,.014368,
-.016464,.015,
-.016064,.015571,
-.015571,.016064,
-.015,.016464,
-.014368,.016759,
-.013695,.016939,
-.013,.017,
.013,.017,
.013695,.016939,
.014368,.016759,
.015,.016464,
.015571,.016064,
.016064,.015571,
.016464,.015,
.016759,.014368,
.016939,.013695,
.017,.013,
0.0*
%
%ADD128MACRO128*%
%AMMACRO80*
4,1,4,.01131,-.0003,
-.0003,-.01131,
-.01131,.0003,
.0003,.01131,
.01131,-.0003,
0.0*
%
%ADD80MACRO80*%
%AMMACRO89*
4,1,4,.01131,-.0003,
-.0003,-.01131,
-.01131,.0003,
.0003,.01131,
.01131,-.0003,
0.0*
%
%ADD89MACRO89*%
%AMMACRO144*
4,1,40,-.011,-.007,
-.011,.007,
-.010939,.007695,
-.010759,.008368,
-.010464,.009,
-.010064,.009571,
-.009571,.010064,
-.009,.010464,
-.008368,.010759,
-.007695,.010939,
-.007,.011,
.007,.011,
.007695,.010939,
.008368,.010759,
.009,.010464,
.009571,.010064,
.010064,.009571,
.010464,.009,
.010759,.008368,
.010939,.007695,
.011,.007,
.011,-.007,
.010939,-.007695,
.010759,-.008368,
.010464,-.009,
.010064,-.009571,
.009571,-.010064,
.009,-.010464,
.008368,-.010759,
.007695,-.010939,
.007,-.011,
-.007,-.011,
-.007695,-.010939,
-.008368,-.010759,
-.009,-.010464,
-.009571,-.010064,
-.010064,-.009571,
-.010464,-.009,
-.010759,-.008368,
-.010939,-.007695,
-.011,-.007,
0.0*
%
%ADD144MACRO144*%
%AMMACRO46*
4,1,40,.007,-.011,
-.007,-.011,
-.007695,-.010939,
-.008368,-.010759,
-.009,-.010464,
-.009571,-.010064,
-.010064,-.009571,
-.010464,-.009,
-.010759,-.008368,
-.010939,-.007695,
-.011,-.007,
-.011,.007,
-.010939,.007695,
-.010759,.008368,
-.010464,.009,
-.010064,.009571,
-.009571,.010064,
-.009,.010464,
-.008368,.010759,
-.007695,.010939,
-.007,.011,
.007,.011,
.007695,.010939,
.008368,.010759,
.009,.010464,
.009571,.010064,
.010064,.009571,
.010464,.009,
.010759,.008368,
.010939,.007695,
.011,.007,
.011,-.007,
.010939,-.007695,
.010759,-.008368,
.010464,-.009,
.010064,-.009571,
.009571,-.010064,
.009,-.010464,
.008368,-.010759,
.007695,-.010939,
.007,-.011,
0.0*
%
%ADD46MACRO46*%
%AMMACRO83*
4,1,4,.01131,-.00022,
-.00022,-.01131,
-.01131,.00022,
.00022,.01131,
.01131,-.00022,
0.0*
%
%ADD83MACRO83*%
%AMMACRO115*
4,1,40,-.0105,-.015,
.0105,-.015,
.011195,-.014939,
.011868,-.014759,
.0125,-.014464,
.013071,-.014064,
.013564,-.013571,
.013964,-.013,
.014259,-.012368,
.014439,-.011695,
.0145,-.011,
.0145,.011,
.014439,.011695,
.014259,.012368,
.013964,.013,
.013564,.013571,
.013071,.014064,
.0125,.014464,
.011868,.014759,
.011195,.014939,
.0105,.015,
-.0105,.015,
-.011195,.014939,
-.011868,.014759,
-.0125,.014464,
-.013071,.014064,
-.013564,.013571,
-.013964,.013,
-.014259,.012368,
-.014439,.011695,
-.0145,.011,
-.0145,-.011,
-.014439,-.011695,
-.014259,-.012368,
-.013964,-.013,
-.013564,-.013571,
-.013071,-.014064,
-.0125,-.014464,
-.011868,-.014759,
-.011195,-.014939,
-.0105,-.015,
0.0*
%
%ADD115MACRO115*%
%ADD18R,.12X.1*%
%ADD31R,.1X.12*%
%AMMACRO20*
4,1,40,-.012,-.008,
-.012,.008,
-.011939,.008695,
-.011759,.009368,
-.011464,.01,
-.011064,.010571,
-.010571,.011064,
-.01,.011464,
-.009368,.011759,
-.008695,.011939,
-.008,.012,
.008,.012,
.008695,.011939,
.009368,.011759,
.01,.011464,
.010571,.011064,
.011064,.010571,
.011464,.01,
.011759,.009368,
.011939,.008695,
.012,.008,
.012,-.008,
.011939,-.008695,
.011759,-.009368,
.011464,-.01,
.011064,-.010571,
.010571,-.011064,
.01,-.011464,
.009368,-.011759,
.008695,-.011939,
.008,-.012,
-.008,-.012,
-.008695,-.011939,
-.009368,-.011759,
-.01,-.011464,
-.010571,-.011064,
-.011064,-.010571,
-.011464,-.01,
-.011759,-.009368,
-.011939,-.008695,
-.012,-.008,
0.0*
%
%ADD20MACRO20*%
%AMMACRO49*
4,1,40,-.008,.012,
.008,.012,
.008695,.011939,
.009368,.011759,
.01,.011464,
.010571,.011064,
.011064,.010571,
.011464,.01,
.011759,.009368,
.011939,.008695,
.012,.008,
.012,-.008,
.011939,-.008695,
.011759,-.009368,
.011464,-.01,
.011064,-.010571,
.010571,-.011064,
.01,-.011464,
.009368,-.011759,
.008695,-.011939,
.008,-.012,
-.008,-.012,
-.008695,-.011939,
-.009368,-.011759,
-.01,-.011464,
-.010571,-.011064,
-.011064,-.010571,
-.011464,-.01,
-.011759,-.009368,
-.011939,-.008695,
-.012,-.008,
-.012,.008,
-.011939,.008695,
-.011759,.009368,
-.011464,.01,
-.011064,.010571,
-.010571,.011064,
-.01,.011464,
-.009368,.011759,
-.008695,.011939,
-.008,.012,
0.0*
%
%ADD49MACRO49*%
%AMMACRO125*
4,1,40,-.013,.017,
.013,.017,
.013695,.016939,
.014368,.016759,
.015,.016464,
.015571,.016064,
.016064,.015571,
.016464,.015,
.016759,.014368,
.016939,.013695,
.017,.013,
.017,-.013,
.016939,-.013695,
.016759,-.014368,
.016464,-.015,
.016064,-.015571,
.015571,-.016064,
.015,-.016464,
.014368,-.016759,
.013695,-.016939,
.013,-.017,
-.013,-.017,
-.013695,-.016939,
-.014368,-.016759,
-.015,-.016464,
-.015571,-.016064,
-.016064,-.015571,
-.016464,-.015,
-.016759,-.014368,
-.016939,-.013695,
-.017,-.013,
-.017,.013,
-.016939,.013695,
-.016759,.014368,
-.016464,.015,
-.016064,.015571,
-.015571,.016064,
-.015,.016464,
-.014368,.016759,
-.013695,.016939,
-.013,.017,
0.0*
%
%ADD125MACRO125*%
%ADD17R,.02X.02*%
%AMMACRO129*
4,1,40,.017,.013,
.017,-.013,
.016939,-.013695,
.016759,-.014368,
.016464,-.015,
.016064,-.015571,
.015571,-.016064,
.015,-.016464,
.014368,-.016759,
.013695,-.016939,
.013,-.017,
-.013,-.017,
-.013695,-.016939,
-.014368,-.016759,
-.015,-.016464,
-.015571,-.016064,
-.016064,-.015571,
-.016464,-.015,
-.016759,-.014368,
-.016939,-.013695,
-.017,-.013,
-.017,.013,
-.016939,.013695,
-.016759,.014368,
-.016464,.015,
-.016064,.015571,
-.015571,.016064,
-.015,.016464,
-.014368,.016759,
-.013695,.016939,
-.013,.017,
.013,.017,
.013695,.016939,
.014368,.016759,
.015,.016464,
.015571,.016064,
.016064,.015571,
.016464,.015,
.016759,.014368,
.016939,.013695,
.017,.013,
0.0*
%
%ADD129MACRO129*%
%ADD13R,.02X.02*%
%ADD163R,.06X.01*%
%ADD161R,.05X.02*%
%ADD166R,.022X.04*%
%AMMACRO148*
4,1,21,.015,.006,
-.009,.006,
-.010042,.005909,
-.011052,.005638,
-.012,.005196,
-.012857,.004596,
-.013596,.003857,
-.014196,.003,
-.014638,.002052,
-.014909,.001042,
-.015,0.0,
-.014909,-.001042,
-.014638,-.002052,
-.014196,-.003,
-.013596,-.003857,
-.012857,-.004596,
-.012,-.005196,
-.011052,-.005638,
-.010042,-.005909,
-.009,-.006,
.015,-.006,
.015,.006,
0.0*
%
%ADD148MACRO148*%
%ADD140R,.102X.145*%
%ADD16R,.04X.05*%
%AMMACRO153*
4,1,21,.006,-.015,
.006,.009,
.005909,.010042,
.005638,.011052,
.005196,.012,
.004596,.012857,
.003857,.013596,
.003,.014196,
.002052,.014638,
.001042,.014909,
0.0,.015,
-.001042,.014909,
-.002052,.014638,
-.003,.014196,
-.003857,.013596,
-.004596,.012857,
-.005196,.012,
-.005638,.011052,
-.005909,.010042,
-.006,.009,
-.006,-.015,
.006,-.015,
0.0*
%
%ADD153MACRO153*%
%ADD150R,.014X.04*%
%ADD113R,.06X.03*%
%ADD52R,.02X.071*%
%ADD50R,.05X.04*%
%ADD43R,.015X.04*%
%ADD26R,.04X.06*%
%ADD157R,.012X.026*%
%ADD121R,.06X.014*%
%ADD91R,.04X.015*%
%ADD41R,.012X.035*%
%ADD40R,.04X.016*%
%ADD39R,.035X.03*%
%ADD32R,.02X.045*%
%ADD152R,.02X.055*%
%ADD123R,.04X.016*%
%ADD119R,.016X.04*%
%ADD114R,.014X.06*%
%ADD44R,.045X.02*%
%ADD34R,.03X.035*%
%ADD30C,.111*%
%ADD27R,.026X.012*%
%ADD42R,.012X.037*%
%AMMACRO167*
4,1,4,.008,.008,
.008,-.008,
-.008,-.008,
-.008,.008,
.008,.008,
0.0*
%
%ADD167MACRO167*%
%AMMACRO145*
4,1,4,0.0,.01131,
.01131,0.0,
0.0,-.01131,
-.01131,0.0,
0.0,.01131,
0.0*
%
%ADD145MACRO145*%
%AMMACRO93*
4,1,4,-.008,.008,
.008,.008,
.008,-.008,
-.008,-.008,
-.008,.008,
0.0*
%
%ADD93MACRO93*%
%AMMACRO92*
4,1,4,-.01131,0.0,
0.0,.01131,
.01131,0.0,
0.0,-.01131,
-.01131,0.0,
0.0*
%
%ADD92MACRO92*%
%AMMACRO38*
4,1,4,-.008,-.008,
-.008,.008,
.008,.008,
.008,-.008,
-.008,-.008,
0.0*
%
%ADD38MACRO38*%
%ADD35R,.065X.02*%
%ADD29R,.018X.05*%
%ADD158R,.018X.07*%
%AMMACRO136*
4,1,4,.00798,.00801,
.00801,-.00798,
-.00798,-.00801,
-.00801,.00798,
.00798,.00801,
0.0*
%
%ADD136MACRO136*%
%AMMACRO112*
4,1,4,-.00312,-.01087,
-.01087,.00312,
.00312,.01087,
.01087,-.00312,
-.00312,-.01087,
0.0*
%
%ADD112MACRO112*%
%AMMACRO64*
4,1,4,.0111,.00219,
.00219,-.0111,
-.0111,-.00219,
-.00219,.0111,
.0111,.00219,
0.0*
%
%ADD64MACRO64*%
%ADD169R,.016X.037*%
%ADD90R,.07X.018*%
%AMMACRO76*
4,1,4,.00378,.01066,
.01066,-.00378,
-.00378,-.01066,
-.01066,.00378,
.00378,.01066,
0.0*
%
%ADD76MACRO76*%
%AMMACRO69*
4,1,4,-.00378,-.01066,
-.01066,.00378,
.00378,.01066,
.01066,-.00378,
-.00378,-.01066,
0.0*
%
%ADD69MACRO69*%
%ADD25R,.039X.013*%
%ADD164R,.014X.048*%
%ADD160R,.037X.016*%
%ADD120R,.065X.025*%
%AMMACRO60*
4,1,4,-.00274,-.01097,
-.01097,.00274,
.00274,.01097,
.01097,-.00274,
-.00274,-.01097,
0.0*
%
%ADD60MACRO60*%
%AMMACRO149*
4,1,21,-.006,.015,
-.006,-.009,
-.005909,-.010042,
-.005638,-.011052,
-.005196,-.012,
-.004596,-.012857,
-.003857,-.013596,
-.003,-.014196,
-.002052,-.014638,
-.001042,-.014909,
0.0,-.015,
.001042,-.014909,
.002052,-.014638,
.003,-.014196,
.003857,-.013596,
.004596,-.012857,
.005196,-.012,
.005638,-.011052,
.005909,-.010042,
.006,-.009,
.006,.015,
-.006,.015,
0.0*
%
%ADD149MACRO149*%
%ADD141R,.048X.016*%
%ADD11R,.045X.055*%
%ADD173R,.039X.035*%
%ADD165R,.038X.063*%
%ADD162R,.025X.076*%
%AMMACRO155*
4,1,21,.015,.006,
-.009,.006,
-.010042,.005909,
-.011052,.005638,
-.012,.005196,
-.012857,.004596,
-.013596,.003857,
-.014196,.003,
-.014638,.002052,
-.014909,.001042,
-.015,0.0,
-.014909,-.001042,
-.014638,-.002052,
-.014196,-.003,
-.013596,-.003857,
-.012857,-.004596,
-.012,-.005196,
-.011052,-.005638,
-.010042,-.005909,
-.009,-.006,
.015,-.006,
.015,.006,
0.0*
%
%ADD155MACRO155*%
%ADD103R,.085X.015*%
%AMMACRO77*
4,1,4,-.00405,-.01056,
-.01056,.00405,
.00405,.01056,
.01056,-.00405,
-.00405,-.01056,
0.0*
%
%ADD77MACRO77*%
%ADD21R,.055X.045*%
%ADD151R,.076X.025*%
%AMMACRO98*
4,1,4,-.00624,-.00943,
-.00943,.00624,
.00624,.00943,
.00943,-.00624,
-.00624,-.00943,
0.0*
%
%ADD98MACRO98*%
%AMMACRO94*
4,1,21,-.01,.004,
-.010695,.003939,
-.011368,.003759,
-.012,.003464,
-.012571,.003064,
-.013064,.002571,
-.013464,.002,
-.013759,.001368,
-.013939,.000695,
-.014,0.0,
-.013939,-.000695,
-.013759,-.001368,
-.013464,-.002,
-.013064,-.002571,
-.012571,-.003064,
-.012,-.003464,
-.011368,-.003759,
-.010695,-.003939,
-.01,-.004,
.014,-.004,
.014,.004,
-.01,.004,
0.0*
%
%ADD94MACRO94*%
%ADD53R,.035X.039*%
%AMMACRO70*
4,1,4,-.00591,-.00964,
-.00964,.00591,
.00591,.00964,
.00964,-.00591,
-.00591,-.00964,
0.0*
%
%ADD70MACRO70*%
%ADD132R,.059X.036*%
%AMMACRO59*
4,1,4,-.00245,-.01104,
-.01104,.00245,
.00245,.01104,
.01104,-.00245,
-.00245,-.01104,
0.0*
%
%ADD59MACRO59*%
%AMMACRO170*
4,1,4,-.00262,-.011,
-.011,.00262,
.00262,.011,
.011,-.00262,
-.00262,-.011,
0.0*
%
%ADD170MACRO170*%
%AMMACRO147*
4,1,21,.006,-.015,
.006,.009,
.005909,.010042,
.005638,.011052,
.005196,.012,
.004596,.012857,
.003857,.013596,
.003,.014196,
.002052,.014638,
.001042,.014909,
0.0,.015,
-.001042,.014909,
-.002052,.014638,
-.003,.014196,
-.003857,.013596,
-.004596,.012857,
-.005196,.012,
-.005638,.011052,
-.005909,.010042,
-.006,.009,
-.006,-.015,
.006,-.015,
0.0*
%
%ADD147MACRO147*%
%AMMACRO65*
4,1,4,-.01109,-.00221,
-.00221,.01109,
.01109,.00221,
.00221,-.01109,
-.01109,-.00221,
0.0*
%
%ADD65MACRO65*%
%AMMACRO57*
4,1,4,-.00225,-.01108,
-.01108,.00225,
.00225,.01108,
.01108,-.00225,
-.00225,-.01108,
0.0*
%
%ADD57MACRO57*%
%AMMACRO154*
4,1,21,-.015,-.006,
.009,-.006,
.010042,-.005909,
.011052,-.005638,
.012,-.005196,
.012857,-.004596,
.013596,-.003857,
.014196,-.003,
.014638,-.002052,
.014909,-.001042,
.015,0.0,
.014909,.001042,
.014638,.002052,
.014196,.003,
.013596,.003857,
.012857,.004596,
.012,.005196,
.011052,.005638,
.010042,.005909,
.009,.006,
-.015,.006,
-.015,-.006,
0.0*
%
%ADD154MACRO154*%
%AMMACRO111*
4,1,4,-.00206,-.01112,
-.01112,.00206,
.00206,.01112,
.01112,-.00206,
-.00206,-.01112,
0.0*
%
%ADD111MACRO111*%
%AMMACRO56*
4,1,4,-.00635,-.00936,
-.00936,.00635,
.00635,.00936,
.00936,-.00635,
-.00635,-.00936,
0.0*
%
%ADD56MACRO56*%
%AMMACRO146*
4,1,21,-.015,-.006,
.009,-.006,
.010042,-.005909,
.011052,-.005638,
.012,-.005196,
.012857,-.004596,
.013596,-.003857,
.014196,-.003,
.014638,-.002052,
.014909,-.001042,
.015,0.0,
.014909,.001042,
.014638,.002052,
.014196,.003,
.013596,.003857,
.012857,.004596,
.012,.005196,
.011052,.005638,
.010042,.005909,
.009,.006,
-.015,.006,
-.015,-.006,
0.0*
%
%ADD146MACRO146*%
%AMMACRO156*
4,1,21,-.006,.015,
-.006,-.009,
-.005909,-.010042,
-.005638,-.011052,
-.005196,-.012,
-.004596,-.012857,
-.003857,-.013596,
-.003,-.014196,
-.002052,-.014638,
-.001042,-.014909,
0.0,-.015,
.001042,-.014909,
.002052,-.014638,
.003,-.014196,
.003857,-.013596,
.004596,-.012857,
.005196,-.012,
.005638,-.011052,
.005909,-.010042,
.006,-.009,
.006,.015,
-.006,.015,
0.0*
%
%ADD156MACRO156*%
%AMMACRO133*
4,1,4,-.00803,-.00796,
-.00796,.00803,
.00803,.00796,
.00796,-.00803,
-.00803,-.00796,
0.0*
%
%ADD133MACRO133*%
%AMMACRO118*
4,1,40,.024,-.012,
.024,.012,
.023878,.013389,
.023518,.014736,
.022928,.016,
.022128,.017142,
.021142,.018128,
.02,.018928,
.018736,.019518,
.017389,.019878,
.016,.02,
-.016,.02,
-.017389,.019878,
-.018736,.019518,
-.02,.018928,
-.021142,.018128,
-.022128,.017142,
-.022928,.016,
-.023518,.014736,
-.023878,.013389,
-.024,.012,
-.024,-.012,
-.023878,-.013389,
-.023518,-.014736,
-.022928,-.016,
-.022128,-.017142,
-.021142,-.018128,
-.02,-.018928,
-.018736,-.019518,
-.017389,-.019878,
-.016,-.02,
.016,-.02,
.017389,-.019878,
.018736,-.019518,
.02,-.018928,
.021142,-.018128,
.022128,-.017142,
.022928,-.016,
.023518,-.014736,
.023878,-.013389,
.024,-.012,
0.0*
%
%ADD118MACRO118*%
%AMMACRO97*
4,1,21,-.004,-.01,
-.003939,-.010695,
-.003759,-.011368,
-.003464,-.012,
-.003064,-.012571,
-.002571,-.013064,
-.002,-.013464,
-.001368,-.013759,
-.000695,-.013939,
0.0,-.014,
.000695,-.013939,
.001368,-.013759,
.002,-.013464,
.002571,-.013064,
.003064,-.012571,
.003464,-.012,
.003759,-.011368,
.003939,-.010695,
.004,-.01,
.004,.014,
-.004,.014,
-.004,-.01,
0.0*
%
%ADD97MACRO97*%
%AMMACRO142*
4,1,4,-.00013,.01131,
.01131,.00013,
.00013,-.01131,
-.01131,-.00013,
-.00013,.01131,
0.0*
%
%ADD142MACRO142*%
%AMMACRO139*
4,1,4,-.01131,-.00013,
-.00013,.01131,
.01131,.00013,
.00013,-.01131,
-.01131,-.00013,
0.0*
%
%ADD139MACRO139*%
%AMMACRO137*
4,1,4,-.00791,-.00809,
-.00809,.00791,
.00791,.00809,
.00809,-.00791,
-.00791,-.00809,
0.0*
%
%ADD137MACRO137*%
%AMMACRO135*
4,1,4,.00791,.00809,
.00809,-.00791,
-.00791,-.00809,
-.00809,.00791,
.00791,.00809,
0.0*
%
%ADD135MACRO135*%
%AMMACRO171*
4,1,40,.008,-.012,
-.008,-.012,
-.008695,-.011939,
-.009368,-.011759,
-.01,-.011464,
-.010571,-.011064,
-.011064,-.010571,
-.011464,-.01,
-.011759,-.009368,
-.011939,-.008695,
-.012,-.008,
-.012,.008,
-.011939,.008695,
-.011759,.009368,
-.011464,.01,
-.011064,.010571,
-.010571,.011064,
-.01,.011464,
-.009368,.011759,
-.008695,.011939,
-.008,.012,
.008,.012,
.008695,.011939,
.009368,.011759,
.01,.011464,
.010571,.011064,
.011064,.010571,
.011464,.01,
.011759,.009368,
.011939,.008695,
.012,.008,
.012,-.008,
.011939,-.008695,
.011759,-.009368,
.011464,-.01,
.011064,-.010571,
.010571,-.011064,
.01,-.011464,
.009368,-.011759,
.008695,-.011939,
.008,-.012,
0.0*
%
%ADD171MACRO171*%
%AMMACRO79*
4,1,40,.012,.008,
.012,-.008,
.011939,-.008695,
.011759,-.009368,
.011464,-.01,
.011064,-.010571,
.010571,-.011064,
.01,-.011464,
.009368,-.011759,
.008695,-.011939,
.008,-.012,
-.008,-.012,
-.008695,-.011939,
-.009368,-.011759,
-.01,-.011464,
-.010571,-.011064,
-.011064,-.010571,
-.011464,-.01,
-.011759,-.009368,
-.011939,-.008695,
-.012,-.008,
-.012,.008,
-.011939,.008695,
-.011759,.009368,
-.011464,.01,
-.011064,.010571,
-.010571,.011064,
-.01,.011464,
-.009368,.011759,
-.008695,.011939,
-.008,.012,
.008,.012,
.008695,.011939,
.009368,.011759,
.01,.011464,
.010571,.011064,
.011064,.010571,
.011464,.01,
.011759,.009368,
.011939,.008695,
.012,.008,
0.0*
%
%ADD79MACRO79*%
%AMMACRO51*
4,1,40,-.007,.011,
.007,.011,
.007695,.010939,
.008368,.010759,
.009,.010464,
.009571,.010064,
.010064,.009571,
.010464,.009,
.010759,.008368,
.010939,.007695,
.011,.007,
.011,-.007,
.010939,-.007695,
.010759,-.008368,
.010464,-.009,
.010064,-.009571,
.009571,-.010064,
.009,-.010464,
.008368,-.010759,
.007695,-.010939,
.007,-.011,
-.007,-.011,
-.007695,-.010939,
-.008368,-.010759,
-.009,-.010464,
-.009571,-.010064,
-.010064,-.009571,
-.010464,-.009,
-.010759,-.008368,
-.010939,-.007695,
-.011,-.007,
-.011,.007,
-.010939,.007695,
-.010759,.008368,
-.010464,.009,
-.010064,.009571,
-.009571,.010064,
-.009,.010464,
-.008368,.010759,
-.007695,.010939,
-.007,.011,
0.0*
%
%ADD51MACRO51*%
%AMMACRO122*
4,1,8,-.0082,-.00339,
-.00339,-.0082,
.00339,-.0082,
.00821,-.00339,
.00821,.00339,
.00339,.0082,
-.00339,.0082,
-.0082,.00339,
-.0082,-.00339,
0.0*
%
%ADD122MACRO122*%
%AMMACRO106*
4,1,8,-.0082,.0034,
-.0082,-.0034,
-.0034,-.0082,
.00341,-.0082,
.0082,-.00341,
.0082,.0034,
.0034,.0082,
-.0034,.0082,
-.0082,.0034,
0.0*
%
%ADD106MACRO106*%
%AMMACRO104*
4,1,8,-.0034,-.0082,
.0034,-.0082,
.0082,-.0034,
.0082,.00341,
.00341,.0082,
-.0034,.0082,
-.0082,.0034,
-.0082,-.0034,
-.0034,-.0082,
0.0*
%
%ADD104MACRO104*%
%AMMACRO101*
4,1,40,.011,.007,
.011,-.007,
.010939,-.007695,
.010759,-.008368,
.010464,-.009,
.010064,-.009571,
.009571,-.010064,
.009,-.010464,
.008368,-.010759,
.007695,-.010939,
.007,-.011,
-.007,-.011,
-.007695,-.010939,
-.008368,-.010759,
-.009,-.010464,
-.009571,-.010064,
-.010064,-.009571,
-.010464,-.009,
-.010759,-.008368,
-.010939,-.007695,
-.011,-.007,
-.011,.007,
-.010939,.007695,
-.010759,.008368,
-.010464,.009,
-.010064,.009571,
-.009571,.010064,
-.009,.010464,
-.008368,.010759,
-.007695,.010939,
-.007,.011,
.007,.011,
.007695,.010939,
.008368,.010759,
.009,.010464,
.009571,.010064,
.010064,.009571,
.010464,.009,
.010759,.008368,
.010939,.007695,
.011,.007,
0.0*
%
%ADD101MACRO101*%
%AMMACRO66*
4,1,4,-.01112,-.00208,
-.00208,.01112,
.01112,.00208,
.00208,-.01112,
-.01112,-.00208,
0.0*
%
%ADD66MACRO66*%
%AMMACRO130*
4,1,40,-.017,-.013,
-.017,.013,
-.016939,.013695,
-.016759,.014368,
-.016464,.015,
-.016064,.015571,
-.015571,.016064,
-.015,.016464,
-.014368,.016759,
-.013695,.016939,
-.013,.017,
.013,.017,
.013695,.016939,
.014368,.016759,
.015,.016464,
.015571,.016064,
.016064,.015571,
.016464,.015,
.016759,.014368,
.016939,.013695,
.017,.013,
.017,-.013,
.016939,-.013695,
.016759,-.014368,
.016464,-.015,
.016064,-.015571,
.015571,-.016064,
.015,-.016464,
.014368,-.016759,
.013695,-.016939,
.013,-.017,
-.013,-.017,
-.013695,-.016939,
-.014368,-.016759,
-.015,-.016464,
-.015571,-.016064,
-.016064,-.015571,
-.016464,-.015,
-.016759,-.014368,
-.016939,-.013695,
-.017,-.013,
0.0*
%
%ADD130MACRO130*%
%AMMACRO126*
4,1,40,.013,-.017,
-.013,-.017,
-.013695,-.016939,
-.014368,-.016759,
-.015,-.016464,
-.015571,-.016064,
-.016064,-.015571,
-.016464,-.015,
-.016759,-.014368,
-.016939,-.013695,
-.017,-.013,
-.017,.013,
-.016939,.013695,
-.016759,.014368,
-.016464,.015,
-.016064,.015571,
-.015571,.016064,
-.015,.016464,
-.014368,.016759,
-.013695,.016939,
-.013,.017,
.013,.017,
.013695,.016939,
.014368,.016759,
.015,.016464,
.015571,.016064,
.016064,.015571,
.016464,.015,
.016759,.014368,
.016939,.013695,
.017,.013,
.017,-.013,
.016939,-.013695,
.016759,-.014368,
.016464,-.015,
.016064,-.015571,
.015571,-.016064,
.015,-.016464,
.014368,-.016759,
.013695,-.016939,
.013,-.017,
0.0*
%
%ADD126MACRO126*%
%AMMACRO96*
4,1,21,.004,.01,
.003939,.010695,
.003759,.011368,
.003464,.012,
.003064,.012571,
.002571,.013064,
.002,.013464,
.001368,.013759,
.000695,.013939,
0.0,.014,
-.000695,.013939,
-.001368,.013759,
-.002,.013464,
-.002571,.013064,
-.003064,.012571,
-.003464,.012,
-.003759,.011368,
-.003939,.010695,
-.004,.01,
-.004,-.014,
.004,-.014,
.004,.01,
0.0*
%
%ADD96MACRO96*%
%AMMACRO58*
4,1,4,-.00217,-.0111,
-.0111,.00217,
.00217,.0111,
.0111,-.00217,
-.00217,-.0111,
0.0*
%
%ADD58MACRO58*%
%AMMACRO134*
4,1,4,-.00009,-.01131,
-.01131,.00009,
.00009,.01131,
.01131,-.00009,
-.00009,-.01131,
0.0*
%
%ADD134MACRO134*%
%AMMACRO95*
4,1,21,.01,-.004,
.010695,-.003939,
.011368,-.003759,
.012,-.003464,
.012571,-.003064,
.013064,-.002571,
.013464,-.002,
.013759,-.001368,
.013939,-.000695,
.014,0.0,
.013939,.000695,
.013759,.001368,
.013464,.002,
.013064,.002571,
.012571,.003064,
.012,.003464,
.011368,.003759,
.010695,.003939,
.01,.004,
-.014,.004,
-.014,-.004,
.01,-.004,
0.0*
%
%ADD95MACRO95*%
%AMMACRO172*
4,1,40,.008,-.012,
-.008,-.012,
-.008695,-.011939,
-.009368,-.011759,
-.01,-.011464,
-.010571,-.011064,
-.011064,-.010571,
-.011464,-.01,
-.011759,-.009368,
-.011939,-.008695,
-.012,-.008,
-.012,.008,
-.011939,.008695,
-.011759,.009368,
-.011464,.01,
-.011064,.010571,
-.010571,.011064,
-.01,.011464,
-.009368,.011759,
-.008695,.011939,
-.008,.012,
.008,.012,
.008695,.011939,
.009368,.011759,
.01,.011464,
.010571,.011064,
.011064,.010571,
.011464,.01,
.011759,.009368,
.011939,.008695,
.012,.008,
.012,-.008,
.011939,-.008695,
.011759,-.009368,
.011464,-.01,
.011064,-.010571,
.010571,-.011064,
.01,-.011464,
.009368,-.011759,
.008695,-.011939,
.008,-.012,
0.0*
%
%ADD172MACRO172*%
%AMMACRO78*
4,1,40,.012,.008,
.012,-.008,
.011939,-.008695,
.011759,-.009368,
.011464,-.01,
.011064,-.010571,
.010571,-.011064,
.01,-.011464,
.009368,-.011759,
.008695,-.011939,
.008,-.012,
-.008,-.012,
-.008695,-.011939,
-.009368,-.011759,
-.01,-.011464,
-.010571,-.011064,
-.011064,-.010571,
-.011464,-.01,
-.011759,-.009368,
-.011939,-.008695,
-.012,-.008,
-.012,.008,
-.011939,.008695,
-.011759,.009368,
-.011464,.01,
-.011064,.010571,
-.010571,.011064,
-.01,.011464,
-.009368,.011759,
-.008695,.011939,
-.008,.012,
.008,.012,
.008695,.011939,
.009368,.011759,
.01,.011464,
.010571,.011064,
.011064,.010571,
.011464,.01,
.011759,.009368,
.011939,.008695,
.012,.008,
0.0*
%
%ADD78MACRO78*%
%AMMACRO28*
4,1,40,-.007,.011,
.007,.011,
.007695,.010939,
.008368,.010759,
.009,.010464,
.009571,.010064,
.010064,.009571,
.010464,.009,
.010759,.008368,
.010939,.007695,
.011,.007,
.011,-.007,
.010939,-.007695,
.010759,-.008368,
.010464,-.009,
.010064,-.009571,
.009571,-.010064,
.009,-.010464,
.008368,-.010759,
.007695,-.010939,
.007,-.011,
-.007,-.011,
-.007695,-.010939,
-.008368,-.010759,
-.009,-.010464,
-.009571,-.010064,
-.010064,-.009571,
-.010464,-.009,
-.010759,-.008368,
-.010939,-.007695,
-.011,-.007,
-.011,.007,
-.010939,.007695,
-.010759,.008368,
-.010464,.009,
-.010064,.009571,
-.009571,.010064,
-.009,.010464,
-.008368,.010759,
-.007695,.010939,
-.007,.011,
0.0*
%
%ADD28MACRO28*%
%ADD174C,.02*%
%ADD175C,.006*%
G75*
%LPD*%
G75*
G36*
G01X13796Y458570D02*
Y449570D01*
X3896D01*
Y450870D01*
X6996D01*
Y452137D01*
X3896D01*
Y453437D01*
X6996D01*
Y454703D01*
X3896D01*
Y456003D01*
X6996D01*
Y457270D01*
X3896D01*
Y458570D01*
X13796D01*
G37*
G36*
G01X1835886Y67776D02*
Y58776D01*
X1825986D01*
Y60076D01*
X1829086D01*
Y61343D01*
X1825986D01*
Y62643D01*
X1829086D01*
Y63909D01*
X1825986D01*
Y65209D01*
X1829086D01*
Y66476D01*
X1825986D01*
Y67776D01*
X1835886D01*
G37*
G36*
G01X22900Y477898D02*
Y484198D01*
X26400D01*
Y477898D01*
X22900D01*
G37*
G36*
G01X1357050Y337050D02*
Y351550D01*
X1371550D01*
Y337050D01*
X1357050D01*
G37*
G36*
G01X1760017Y567440D02*
Y560240D01*
X1752817D01*
Y567440D01*
X1760017D01*
G37*
G36*
G01X1813652Y539601D02*
Y532401D01*
X1806452D01*
Y539601D01*
X1813652D01*
G37*
G36*
G01X1814152Y590401D02*
X1806952D01*
Y597601D01*
X1814152D01*
Y590401D01*
G37*
G36*
G01X1878090Y49550D02*
X1871790D01*
Y53050D01*
X1878090D01*
Y49550D01*
G37*
G54D100*
X1449933Y49950D03*
X1469689Y49000D03*
X1697872Y116423D03*
X1682141Y136233D03*
X1705138Y114470D03*
X1709277Y120700D03*
G54D101*
X1457000Y101300D03*
X1474100Y234400D03*
X1585849Y105088D03*
X1582849Y96088D03*
X1825700Y26300D03*
X1938600Y455317D03*
G54D110*
X1465100Y521800D03*
Y516100D03*
X1465000Y537850D03*
Y532150D03*
X1498000Y525200D03*
Y519500D03*
X1487700Y537900D03*
Y532200D03*
X1611300Y491500D03*
Y497200D03*
X1606800Y474700D03*
Y480400D03*
G54D111*
X1446392Y472057D03*
X1438283Y472592D03*
G54D120*
X1567299Y215920D03*
Y210920D03*
Y205920D03*
Y200920D03*
Y195920D03*
Y190920D03*
Y185920D03*
X1530149D03*
Y190920D03*
Y195920D03*
Y200920D03*
Y205920D03*
Y210920D03*
Y215920D03*
X1567299Y220920D03*
X1530149D03*
G54D102*
X1457000Y104700D03*
X1474100Y237800D03*
X1585849Y108488D03*
X1582849Y99488D03*
X1825700Y29700D03*
X1938600Y458717D03*
G54D130*
X1616849Y104338D03*
G54D103*
X1456250Y209500D03*
X1432750Y217180D03*
Y209500D03*
Y201820D03*
X1456250D03*
Y217180D03*
Y204380D03*
Y206940D03*
Y212060D03*
Y214620D03*
X1432750Y204380D03*
Y206940D03*
Y212060D03*
Y214620D03*
X1457838Y176527D03*
X1434338Y184207D03*
Y176527D03*
Y168847D03*
X1457838D03*
Y184207D03*
Y171407D03*
Y173967D03*
Y179087D03*
Y181647D03*
X1434338Y171407D03*
Y173967D03*
Y179087D03*
Y181647D03*
X1458250Y232000D03*
X1434750Y239680D03*
Y232000D03*
Y224320D03*
X1458250D03*
Y239680D03*
Y226880D03*
Y229440D03*
Y234560D03*
Y237120D03*
X1434750Y226880D03*
Y229440D03*
Y234560D03*
Y237120D03*
X1484750Y205750D03*
Y198250D03*
X1506250Y200750D03*
Y208250D03*
X1484750Y215750D03*
X1506250D03*
X1484750Y208250D03*
Y210750D03*
Y200750D03*
Y203250D03*
X1506250D03*
Y205750D03*
Y210750D03*
Y213250D03*
Y198250D03*
X1484750Y213250D03*
X1485450Y232250D03*
Y224750D03*
X1506950Y227250D03*
Y234750D03*
X1485450Y242250D03*
X1506950D03*
X1485450Y234750D03*
Y237250D03*
Y227250D03*
Y229750D03*
X1506950D03*
Y232250D03*
Y237250D03*
Y239750D03*
Y224750D03*
X1485450Y239750D03*
X1703250Y62680D03*
Y55000D03*
Y47320D03*
Y49880D03*
Y52440D03*
Y57560D03*
Y60120D03*
X1726750Y55000D03*
Y47320D03*
Y62680D03*
Y49880D03*
Y52440D03*
Y57560D03*
Y60120D03*
G54D112*
X1410808Y472742D03*
G54D121*
X1589000Y298000D03*
X1572820D03*
X1589000Y303120D03*
X1572820D03*
X1589000Y300560D03*
X1572820D03*
Y305680D03*
X1589000D03*
X1864804Y568068D03*
Y565508D03*
Y562948D03*
X1887004Y542468D03*
Y545028D03*
Y547588D03*
Y550148D03*
Y552708D03*
Y555268D03*
X1864804Y557828D03*
Y555268D03*
Y552708D03*
Y550148D03*
Y547588D03*
Y545028D03*
Y542468D03*
Y539908D03*
X1887004Y557828D03*
Y560388D03*
Y568068D03*
Y539908D03*
Y562948D03*
Y565508D03*
X1864804Y560388D03*
G36*
G01X25Y11900D02*
G02X0Y-11900I-25J-11900D01*
G02X-25Y11900I0J11900D01*
G01Y11200D01*
G03X0Y-11200I25J-11200D01*
G03X25Y11200I0J11200D01*
G01Y11900D01*
G37*
G54D104*
X1456476Y278324D03*
Y275174D03*
X1459627Y300373D03*
Y297223D03*
X1481672Y278329D03*
Y275179D03*
X1475365Y300366D03*
Y297216D03*
X1468429Y289284D03*
Y286134D03*
X1472223Y287778D03*
Y284628D03*
X1481672Y306679D03*
Y303529D03*
X1520225Y440375D03*
Y437225D03*
X1517075Y443525D03*
Y440375D03*
X1523375D03*
Y437225D03*
X1526525Y440375D03*
Y437225D03*
X1513925Y443525D03*
Y440375D03*
X1510775Y443525D03*
Y440375D03*
X1504240Y416556D03*
Y413406D03*
X1532825Y452975D03*
Y449825D03*
X1539125Y452975D03*
Y449825D03*
X1542275Y440375D03*
Y437225D03*
X1535975Y440375D03*
Y437225D03*
X1532825Y440375D03*
Y437225D03*
X1539125Y421475D03*
Y418325D03*
X1532825Y421475D03*
Y418325D03*
G54D122*
X1548127Y414127D03*
X1545900Y411900D03*
G54D11*
X-16100Y25200D03*
X-16016Y45478D03*
X-15700Y35500D03*
X-15950Y55460D03*
X-8500Y25200D03*
X-8416Y45478D03*
X-8100Y35500D03*
X-8350Y55460D03*
X722268Y35902D03*
X720800Y523000D03*
X729868Y35902D03*
X751800Y213500D03*
X744200D03*
X728400Y523000D03*
X1390831Y97354D03*
X1383231D03*
X1398120Y378198D03*
Y370363D03*
X1374084Y555453D03*
X1366484D03*
X1396115Y557832D03*
X1388515D03*
X1396115Y565472D03*
X1388515D03*
X1395490Y532250D03*
X1403090D03*
X1395862Y542932D03*
X1403462D03*
X1405720Y378198D03*
Y370363D03*
X1464300Y598500D03*
X1456700D03*
X1872100Y162100D03*
X1879700D03*
X1872140Y169749D03*
X1879740D03*
X1870900Y179700D03*
X1878500D03*
X1871000Y191100D03*
X1878600D03*
G54D113*
X1490300Y22700D03*
X1478300D03*
X1906000Y564600D03*
X1918000D03*
X1906000Y582000D03*
X1918000D03*
X1906000Y573300D03*
X1918000D03*
X1906000Y590700D03*
X1918000D03*
G54D140*
X1660158Y539547D03*
X1788110D03*
G54D20*
X20340Y24559D03*
X16720Y53240D03*
X6840Y564000D03*
X8530Y529080D03*
X130564Y209283D03*
X130774Y241333D03*
X130250Y273300D03*
X130574Y305323D03*
Y337533D03*
X130834Y369363D03*
X780152Y209163D03*
X780182Y241283D03*
Y273533D03*
X780892Y305563D03*
X780722Y337353D03*
X780112Y369433D03*
G54D131*
X1616849Y98738D03*
G54D132*
X1595943Y441200D03*
Y447800D03*
G54D21*
X46777Y-16430D03*
Y-8830D03*
X35677Y-16430D03*
Y-8830D03*
X706270Y243945D03*
Y236345D03*
X714900Y244090D03*
Y236490D03*
X723604Y237024D03*
Y229424D03*
X736500Y208700D03*
Y216300D03*
X732344Y237043D03*
Y229443D03*
X741055Y241836D03*
Y234236D03*
X1380000Y414300D03*
Y406700D03*
X1372000Y414300D03*
Y406700D03*
X1364000Y414300D03*
Y406700D03*
X1388000Y414300D03*
Y406700D03*
X1356655Y523455D03*
Y531055D03*
X1398950Y574260D03*
Y581860D03*
X1429261Y568923D03*
Y576523D03*
X1437013Y568923D03*
Y576523D03*
X1409404Y574063D03*
Y581663D03*
X1448526Y593422D03*
Y601022D03*
X1456694Y618570D03*
Y610970D03*
X1448694Y618570D03*
Y610970D03*
X1440694Y618570D03*
Y610970D03*
X1922224Y216107D03*
X1914569Y216096D03*
X1922224Y223707D03*
X1914569Y223696D03*
X1968487Y214193D03*
Y221793D03*
G54D141*
X1756750Y81060D03*
Y75940D03*
X1763250Y78500D03*
Y75940D03*
Y81060D03*
G54D30*
X94683Y13078D03*
Y50878D03*
Y88678D03*
Y514079D03*
Y589679D03*
Y551879D03*
X637793Y13078D03*
Y50878D03*
Y88678D03*
Y514079D03*
Y589679D03*
Y551879D03*
X744293Y13078D03*
Y88678D03*
Y50878D03*
Y514079D03*
Y589679D03*
Y551879D03*
X1287403Y13078D03*
Y88678D03*
Y50878D03*
Y514079D03*
Y589679D03*
Y551879D03*
G54D114*
X1527233Y57198D03*
Y41018D03*
X1551107Y65716D03*
X1548547D03*
X1545987D03*
X1543427D03*
Y49536D03*
X1545987D03*
X1548547D03*
X1551107D03*
X1534913Y57198D03*
X1532353D03*
X1529793D03*
Y41018D03*
X1532353D03*
X1534913D03*
G54D123*
X1651250Y31059D03*
Y28500D03*
Y25941D03*
X1658750D03*
Y31059D03*
Y28500D03*
G54D150*
X1730814Y565314D03*
X1728254Y575914D03*
X1733369D03*
X1725694D03*
X1730814D03*
X1733369Y565314D03*
X1728254D03*
X1725694D03*
G54D105*
X1450182Y275181D03*
Y278331D03*
X1459628Y281473D03*
Y284623D03*
X1462777Y294072D03*
Y297222D03*
X1462775Y281470D03*
Y284620D03*
X1465949Y294050D03*
Y297200D03*
X1484822Y275177D03*
Y278327D03*
X1478523Y303521D03*
Y306671D03*
X1469000Y294100D03*
Y297250D03*
X1472226Y294076D03*
Y297226D03*
X1475373Y284626D03*
Y287776D03*
X1523375Y443525D03*
Y446675D03*
X1510775Y415175D03*
Y418325D03*
X1507625Y415175D03*
Y418325D03*
X1539125Y443525D03*
Y446675D03*
X1535975Y443525D03*
Y446675D03*
X1549805Y416465D03*
Y419615D03*
X1535975Y421475D03*
Y424625D03*
X1539125Y412025D03*
Y415175D03*
G54D12*
X-15250Y71330D03*
X-5210D03*
G54D106*
X1462770Y287777D03*
X1459620D03*
X1456477Y303528D03*
X1453327D03*
X1525900Y452400D03*
X1520225Y424625D03*
X1517075D03*
X1520225Y427775D03*
X1517075D03*
X1523550Y411600D03*
X1520400D03*
X1520225Y421475D03*
X1517075D03*
X1529050Y452400D03*
X1554875Y434075D03*
X1551725D03*
X1542275Y424625D03*
X1539125D03*
X1542275Y427775D03*
X1539125D03*
X1546000Y406800D03*
X1542850D03*
G54D142*
X1715318Y128300D03*
G54D133*
X1706065Y141740D03*
X1707042Y147319D03*
G54D151*
X1780700Y89500D03*
Y94500D03*
X1802300D03*
Y89500D03*
X1780700Y99500D03*
X1802300D03*
Y104500D03*
X1780700D03*
G54D160*
X1874087Y487232D03*
X1961401Y184141D03*
G54D40*
X94900Y332800D03*
X103900D03*
X94010Y343470D03*
X103010D03*
X1496800Y324500D03*
Y327060D03*
X1504200Y324500D03*
Y327060D03*
Y321940D03*
X1496800D03*
X1554500Y109940D03*
X1561900D03*
X1554500Y107380D03*
X1561900D03*
X1554500Y112500D03*
X1561900D03*
X1647500Y16500D03*
X1611900Y55500D03*
X1619300D03*
X1611900Y52940D03*
X1619300D03*
X1611900Y58060D03*
X1619300D03*
X1656500Y16500D03*
X1768628Y62395D03*
X1777628D03*
G54D13*
X-17190Y471340D03*
Y474840D03*
X41542Y16578D03*
Y13078D03*
X44542Y16578D03*
Y13078D03*
X7600Y29800D03*
Y33300D03*
X41000Y271400D03*
Y267900D03*
X37000Y271400D03*
Y267900D03*
X46900Y298100D03*
Y294600D03*
X-8690Y460640D03*
Y464140D03*
X-13690Y460640D03*
Y464140D03*
X-5690Y473840D03*
Y470340D03*
X-8690Y473840D03*
Y470340D03*
X-500Y517500D03*
Y521000D03*
X-3500Y517500D03*
Y521000D03*
X31600Y517600D03*
Y521100D03*
X-12690Y481740D03*
Y478240D03*
X-9190Y481740D03*
Y478240D03*
X-12190Y471140D03*
Y467640D03*
X-2600Y538900D03*
Y542400D03*
X105700Y122000D03*
Y118500D03*
X102400D03*
Y122000D03*
X71500Y176500D03*
Y180000D03*
X75000Y176500D03*
Y180000D03*
X85500Y278500D03*
Y275000D03*
X80500Y278500D03*
Y275000D03*
X106600Y307000D03*
Y303500D03*
X69000Y341800D03*
X57000Y341500D03*
X91000Y317500D03*
Y321000D03*
X56000Y296200D03*
Y299700D03*
X94000Y307000D03*
Y303500D03*
X97500D03*
Y307000D03*
X89000Y309500D03*
Y306000D03*
X72000Y341800D03*
X101000Y303500D03*
Y307000D03*
X87500Y317500D03*
Y321000D03*
X69000Y292500D03*
Y289000D03*
X72500Y292500D03*
Y289000D03*
X69000Y345300D03*
X57000Y345000D03*
X75000Y372600D03*
Y376100D03*
X79500Y372600D03*
Y376100D03*
X72000Y345300D03*
X52601Y483087D03*
Y486587D03*
X106392Y534500D03*
Y531000D03*
X105392Y572300D03*
Y568800D03*
X105892Y612000D03*
Y608500D03*
X122000Y256500D03*
Y253000D03*
Y222900D03*
Y219400D03*
X122100Y287600D03*
Y284100D03*
Y320400D03*
Y316900D03*
X121800Y345800D03*
Y349300D03*
X121862Y377600D03*
Y381100D03*
X108892Y572300D03*
Y568800D03*
X112392Y572300D03*
Y568800D03*
X116892Y531000D03*
Y534500D03*
X115892Y568800D03*
Y572300D03*
X109892Y534500D03*
Y531000D03*
X113392Y534500D03*
Y531000D03*
X109392Y612000D03*
Y608500D03*
X112892Y612000D03*
Y608500D03*
X116392D03*
Y612000D03*
X195200Y382800D03*
Y386300D03*
X253000Y258600D03*
Y255100D03*
X249000Y258600D03*
Y255100D03*
X461000Y317303D03*
Y320803D03*
X510937Y262947D03*
Y266447D03*
X507400Y264496D03*
Y260996D03*
X514220Y263291D03*
Y266791D03*
X661800Y25500D03*
Y29000D03*
X656500Y-14000D03*
Y-17500D03*
X653150Y-14000D03*
Y-17500D03*
X650050Y-14300D03*
Y-17800D03*
X638500Y270500D03*
Y274000D03*
Y277000D03*
X663500Y254000D03*
Y257500D03*
X638488Y249513D03*
Y246013D03*
X646000Y261500D03*
Y265000D03*
X643823Y286894D03*
Y283394D03*
X639622Y286894D03*
Y283394D03*
X638500Y280500D03*
X654000Y342000D03*
X659000D03*
X649000D03*
X655500Y290000D03*
Y293500D03*
X658617Y288371D03*
Y291871D03*
X661767Y289974D03*
Y293474D03*
X654000Y345500D03*
X659000D03*
X649000D03*
X662000Y488500D03*
Y485000D03*
X636930Y488050D03*
Y484550D03*
X624700Y484100D03*
Y487600D03*
X632930Y484550D03*
Y488050D03*
X618430Y485050D03*
Y488550D03*
X614430Y485050D03*
Y488550D03*
X631600Y477600D03*
Y481100D03*
X614930Y481550D03*
Y478050D03*
X618430Y481550D03*
Y478050D03*
X713937Y-6048D03*
Y-9548D03*
X722937Y17452D03*
Y20952D03*
X719437Y17452D03*
Y20952D03*
X711233Y82298D03*
Y78798D03*
X707893Y82298D03*
Y78798D03*
X694000Y76000D03*
Y79500D03*
X716500Y53500D03*
Y50000D03*
X710500Y252500D03*
Y256000D03*
X673500Y291500D03*
Y295000D03*
X683000Y291300D03*
Y294800D03*
X684000Y342000D03*
X674000D03*
X679000D03*
X669000D03*
X722500Y283300D03*
Y286800D03*
X700500Y308000D03*
Y311500D03*
X664000Y342000D03*
X668500Y332500D03*
Y336000D03*
X684000Y345500D03*
X689000Y352500D03*
Y349000D03*
X693000Y352500D03*
Y349000D03*
X674000Y345500D03*
X679000D03*
X669000D03*
X664000D03*
X680500Y493000D03*
Y496500D03*
X673464Y503784D03*
Y507284D03*
X716000Y577500D03*
Y574000D03*
X722500Y577500D03*
Y574000D03*
X716400Y538800D03*
Y535300D03*
X728500Y283500D03*
Y287000D03*
X769600Y407600D03*
Y404100D03*
X766300Y407700D03*
Y404200D03*
X763200Y407700D03*
Y404200D03*
X765500Y568800D03*
Y572300D03*
X762000D03*
Y568800D03*
X759500Y534500D03*
Y531000D03*
X766500D03*
Y534500D03*
X763000D03*
Y531000D03*
X758500Y572300D03*
Y568800D03*
X755000Y572300D03*
Y568800D03*
X756000Y534500D03*
Y531000D03*
X759000Y612000D03*
Y608500D03*
X762500Y612000D03*
Y608500D03*
X766000D03*
Y612000D03*
X727000Y600500D03*
Y604000D03*
X755500Y612000D03*
Y608500D03*
X844808Y382800D03*
Y386300D03*
X899450Y258050D03*
Y254550D03*
X903050Y257950D03*
Y254450D03*
X1156980Y260920D03*
Y264420D03*
X1157013Y254048D03*
Y257548D03*
X1110300Y317800D03*
Y321300D03*
X1218254Y113956D03*
Y110456D03*
X1164900Y264826D03*
Y268326D03*
X1224924Y110448D03*
Y113948D03*
X1221682Y110456D03*
Y113956D03*
X1231442Y121275D03*
Y124775D03*
X1236600Y124877D03*
Y121377D03*
X1250890Y497310D03*
Y493810D03*
X1254390D03*
Y497310D03*
X1264700Y492143D03*
Y488643D03*
X1301500Y20000D03*
Y23500D03*
X1297000Y29500D03*
Y33000D03*
X1301100Y42600D03*
Y46100D03*
X1304500Y42600D03*
Y46100D03*
X1303697Y145379D03*
Y148879D03*
X1307197Y145379D03*
Y148879D03*
X1339889Y234171D03*
Y237671D03*
X1330800Y220450D03*
Y223950D03*
X1334389Y234171D03*
Y237671D03*
X1312389Y234171D03*
Y237671D03*
X1317889Y234171D03*
Y237671D03*
X1323389Y234171D03*
Y237671D03*
X1328889Y234171D03*
Y237671D03*
X1334389D03*
Y241171D03*
X1339889Y237671D03*
Y241171D03*
X1317889Y237671D03*
Y241171D03*
X1323389Y237671D03*
Y241171D03*
X1328889Y237671D03*
Y241171D03*
X1312389Y237671D03*
Y241171D03*
X1339800Y336800D03*
Y340300D03*
X1322430Y337460D03*
Y333960D03*
X1327400Y333930D03*
Y337430D03*
X1339240Y309384D03*
Y305884D03*
Y302384D03*
Y305884D03*
X1333740Y309384D03*
Y305884D03*
Y302384D03*
Y305884D03*
X1339800Y346800D03*
Y343300D03*
X1337600Y442100D03*
Y438600D03*
X1375500Y68500D03*
Y65000D03*
X1376500Y113600D03*
Y110100D03*
X1394889Y234171D03*
Y237671D03*
X1378389Y234171D03*
Y237671D03*
X1367389Y234171D03*
Y237671D03*
X1372889Y234171D03*
Y237671D03*
X1361889Y234171D03*
Y237671D03*
X1356389Y234171D03*
Y237671D03*
X1389389Y234171D03*
Y237671D03*
X1350889Y234171D03*
Y237671D03*
X1345389Y234171D03*
Y237671D03*
X1383889Y234171D03*
Y237671D03*
X1394889D03*
Y241171D03*
X1350889Y237671D03*
Y241171D03*
X1389389Y237671D03*
Y241171D03*
X1383889Y237671D03*
Y241171D03*
X1378389Y237671D03*
Y241171D03*
X1367389Y237671D03*
Y241171D03*
X1372889Y237671D03*
Y241171D03*
X1361889Y237671D03*
Y241171D03*
X1356389Y237671D03*
Y241171D03*
X1345389Y237671D03*
Y241171D03*
X1357000Y329000D03*
Y325500D03*
X1353500D03*
Y329000D03*
X1395135Y310254D03*
Y306754D03*
Y303254D03*
Y306754D03*
X1400537Y310254D03*
Y306754D03*
Y303254D03*
Y306754D03*
X1371000Y325400D03*
Y328900D03*
X1374500Y325400D03*
Y328900D03*
X1350000Y325500D03*
Y329000D03*
X1361544Y309384D03*
Y305884D03*
X1356044Y302384D03*
Y305884D03*
X1361544Y302384D03*
Y305884D03*
X1383548Y309934D03*
Y306434D03*
X1389635Y303254D03*
Y306754D03*
X1383548Y302934D03*
Y306434D03*
X1389635Y310254D03*
Y306754D03*
X1378048Y302934D03*
Y306434D03*
Y309934D03*
Y306434D03*
X1345142Y309384D03*
Y305884D03*
X1350642Y309384D03*
Y305884D03*
X1345142Y302384D03*
Y305884D03*
X1350642Y302384D03*
Y305884D03*
X1366840Y302754D03*
Y306254D03*
X1372340Y302754D03*
Y306254D03*
X1366840Y309754D03*
Y306254D03*
X1372340Y309754D03*
Y306254D03*
X1356044Y309384D03*
Y305884D03*
X1396052Y357720D03*
Y354220D03*
X1391212Y357760D03*
Y354260D03*
X1348988Y355077D03*
Y351577D03*
X1387500Y423600D03*
Y427100D03*
X1371500Y526000D03*
Y529500D03*
X1379100Y578000D03*
Y574500D03*
X1379200Y609300D03*
Y605800D03*
X1455100Y24550D03*
Y21050D03*
X1451600Y24550D03*
Y21050D03*
X1464500Y20750D03*
Y24250D03*
X1448600Y24550D03*
Y21050D03*
X1416800Y16700D03*
Y20200D03*
X1413800Y16700D03*
Y20200D03*
X1410800Y16700D03*
Y20200D03*
X1457000Y108500D03*
Y112000D03*
X1445500Y153300D03*
Y156800D03*
X1447391Y142729D03*
Y139229D03*
X1447428Y145543D03*
Y149043D03*
X1463900Y205550D03*
Y202050D03*
X1465234Y183258D03*
Y186758D03*
X1462059Y191683D03*
Y188183D03*
X1426261Y176309D03*
Y179809D03*
Y163309D03*
Y166809D03*
X1445500Y163300D03*
Y159800D03*
X1426261Y169809D03*
Y173309D03*
Y186309D03*
Y182809D03*
X1438500Y163300D03*
Y159800D03*
X1442000Y163300D03*
Y159800D03*
X1464500Y262100D03*
Y258600D03*
X1454500Y251250D03*
Y247750D03*
X1458500Y249000D03*
Y245500D03*
X1443000Y248750D03*
Y245250D03*
X1446000Y248750D03*
Y245250D03*
X1440000Y248750D03*
Y245250D03*
X1458011Y264408D03*
Y267908D03*
X1460835Y261026D03*
Y257526D03*
X1457835D03*
Y261026D03*
X1430900Y250350D03*
Y246850D03*
X1406037Y303254D03*
Y306754D03*
X1411220Y310284D03*
Y306784D03*
X1416720Y310284D03*
Y306784D03*
Y303284D03*
Y306784D03*
X1411220Y303284D03*
Y306784D03*
X1406037Y310254D03*
Y306754D03*
X1460868Y373393D03*
Y369893D03*
X1425600Y523700D03*
X1422000D03*
X1416600Y524500D03*
X1460600Y521100D03*
Y517600D03*
X1425600Y527200D03*
X1422000D03*
X1416600Y528000D03*
X1460500Y537500D03*
Y534000D03*
X1468000Y20750D03*
Y24250D03*
X1471500Y20750D03*
Y24250D03*
X1505500Y9641D03*
Y6141D03*
X1502300Y9641D03*
Y6141D03*
X1487000Y83500D03*
Y80000D03*
Y73500D03*
Y77000D03*
X1520904Y51355D03*
Y47855D03*
X1486193Y103797D03*
Y107297D03*
X1485150Y148500D03*
Y145000D03*
X1466188Y171277D03*
Y167777D03*
X1471988Y166677D03*
Y170177D03*
X1467992Y205635D03*
Y202135D03*
X1480988Y166677D03*
Y170177D03*
X1477988Y166677D03*
Y170177D03*
X1474988Y166677D03*
Y170177D03*
X1484100Y177700D03*
Y174200D03*
X1493700Y185400D03*
Y181900D03*
X1487230Y261150D03*
Y264650D03*
X1490310Y261140D03*
Y264640D03*
X1478000Y263500D03*
Y260000D03*
X1484000Y263500D03*
Y260000D03*
X1481000D03*
Y263500D03*
X1493450Y261140D03*
Y264640D03*
X1472000Y260000D03*
Y263500D03*
X1475000D03*
Y260000D03*
X1477500Y219350D03*
Y222850D03*
X1476800Y231000D03*
Y227500D03*
X1470554Y236923D03*
Y233423D03*
X1478424Y241688D03*
Y245188D03*
X1467054Y236923D03*
Y233423D03*
X1518952Y337082D03*
Y333582D03*
X1521952Y337082D03*
Y333582D03*
X1490500Y336000D03*
Y339500D03*
X1502850Y336900D03*
Y333400D03*
X1515952Y337082D03*
Y333582D03*
X1512952Y337082D03*
Y333582D03*
X1490000Y332100D03*
Y328600D03*
X1523000Y347250D03*
Y343750D03*
X1520000Y347250D03*
Y343750D03*
X1526000Y347250D03*
Y343750D03*
X1466967Y353465D03*
Y349965D03*
X1477500Y348750D03*
Y352250D03*
X1474049Y350889D03*
Y347389D03*
X1499000Y347250D03*
Y343750D03*
X1496000Y347250D03*
Y343750D03*
X1493000Y347250D03*
Y343750D03*
X1481000Y343250D03*
Y346750D03*
X1494023Y361853D03*
Y358353D03*
X1475500Y358750D03*
Y355250D03*
X1505000Y347250D03*
Y343750D03*
X1502000Y347250D03*
Y343750D03*
X1481164Y359387D03*
Y362887D03*
X1517000Y346650D03*
Y343150D03*
X1502800Y356420D03*
Y359920D03*
X1470467Y349965D03*
Y353465D03*
X1486572Y432791D03*
Y436291D03*
X1506800Y454500D03*
Y451000D03*
X1479150Y430678D03*
Y434178D03*
X1522870Y503200D03*
Y499700D03*
X1525700Y515310D03*
Y511810D03*
X1483700Y521700D03*
Y518200D03*
X1476600Y523100D03*
Y519600D03*
X1478000Y527250D03*
Y530750D03*
X1483200Y537200D03*
Y533700D03*
X1494800Y536700D03*
Y540200D03*
X1472300Y608439D03*
Y611939D03*
X1507952Y608439D03*
Y611939D03*
X1549000Y74450D03*
Y77950D03*
X1562909Y64718D03*
Y68218D03*
X1559909Y64718D03*
Y68218D03*
X1544814Y77485D03*
Y80985D03*
X1551050Y39445D03*
Y42945D03*
X1548050Y39445D03*
Y42945D03*
X1577431Y90987D03*
Y87487D03*
X1586149Y94288D03*
X1557277Y49563D03*
Y46063D03*
X1580531Y87500D03*
Y91000D03*
X1588000Y138500D03*
Y142000D03*
X1579167Y107718D03*
Y104218D03*
X1568000Y111500D03*
Y108000D03*
X1565500Y152500D03*
Y149000D03*
X1562500Y152500D03*
Y149000D03*
X1547400Y149700D03*
Y146200D03*
X1561709Y124081D03*
Y120581D03*
X1552171Y130471D03*
Y126971D03*
X1566481Y127454D03*
Y130954D03*
X1582649Y103288D03*
Y106788D03*
X1586149Y97788D03*
X1551858Y98991D03*
Y102491D03*
X1576414Y117787D03*
Y121287D03*
X1588156Y125638D03*
Y129138D03*
X1576040Y210090D03*
Y213590D03*
X1574500Y217000D03*
X1579540Y210090D03*
Y213590D03*
X1583190Y210070D03*
Y213570D03*
X1574500Y220500D03*
Y223500D03*
Y227000D03*
X1535966Y337018D03*
Y333518D03*
X1539000Y337000D03*
Y333500D03*
X1582000Y292500D03*
Y289000D03*
X1585000Y292500D03*
Y289000D03*
X1539000Y340750D03*
X1556500Y334750D03*
Y338250D03*
X1553500Y334750D03*
Y338250D03*
X1545000Y340750D03*
X1563000Y338250D03*
Y334750D03*
X1566000Y338250D03*
Y334750D03*
X1542000Y340750D03*
X1536000D03*
X1533000D03*
X1584000Y347250D03*
Y343750D03*
X1581000Y347250D03*
Y343750D03*
X1539000Y344250D03*
X1553500Y343750D03*
Y347250D03*
X1556500Y343750D03*
Y347250D03*
X1559500D03*
Y343750D03*
X1545000Y344250D03*
X1529000Y347250D03*
Y343750D03*
X1542000Y344250D03*
X1536000D03*
X1533000D03*
X1562500Y347300D03*
Y343800D03*
X1565500D03*
Y347300D03*
X1568600Y344050D03*
Y347550D03*
X1571800Y347800D03*
Y344300D03*
X1579000Y413250D03*
Y409750D03*
X1579500Y425250D03*
Y421750D03*
X1546596Y441697D03*
Y445197D03*
X1545271Y419162D03*
Y422662D03*
X1573877Y451641D03*
Y455141D03*
X1577782Y451536D03*
Y455036D03*
Y461336D03*
Y457836D03*
X1574377Y457941D03*
Y461441D03*
X1575500Y435000D03*
Y438500D03*
X1586670Y463250D03*
X1528100Y443350D03*
Y446850D03*
X1528500Y420500D03*
Y417000D03*
X1529000Y515310D03*
Y511810D03*
X1588300Y487500D03*
Y484000D03*
X1586670Y466750D03*
X1584500Y586600D03*
Y583100D03*
X1537700Y610897D03*
Y607397D03*
X1644000Y22250D03*
Y25750D03*
Y28750D03*
Y32250D03*
X1613000Y-14218D03*
Y-10718D03*
X1621500Y32750D03*
Y29250D03*
Y22250D03*
Y25750D03*
X1606500Y30750D03*
Y27250D03*
Y20750D03*
Y17250D03*
X1592453Y6002D03*
Y2502D03*
X1641600Y84000D03*
Y87500D03*
Y94000D03*
Y90500D03*
X1602000Y87250D03*
Y90750D03*
X1603800Y54950D03*
Y51450D03*
X1638500Y84000D03*
Y87500D03*
Y94000D03*
Y90500D03*
X1600300Y57950D03*
Y54450D03*
X1641600Y99000D03*
Y102500D03*
X1596865Y145871D03*
Y149371D03*
X1590949Y104288D03*
Y100788D03*
X1597349D03*
Y104288D03*
X1604400Y119300D03*
Y115800D03*
X1604939Y132088D03*
Y128588D03*
X1601400Y113100D03*
Y116600D03*
X1648500Y141750D03*
Y138250D03*
X1644930Y153700D03*
X1641274Y130773D03*
Y127273D03*
X1638500Y99000D03*
Y102500D03*
X1648500Y128750D03*
Y125250D03*
X1632050Y145170D03*
Y148670D03*
X1594149Y100788D03*
Y104288D03*
X1635000Y125750D03*
Y122250D03*
X1648500Y131750D03*
Y135250D03*
X1626900Y144300D03*
Y147800D03*
X1591356Y125638D03*
Y129138D03*
X1639649Y179288D03*
Y175788D03*
X1642649Y179288D03*
Y175788D03*
X1648349D03*
Y179288D03*
X1636649D03*
Y175788D03*
X1625000Y177808D03*
Y181308D03*
X1610500Y188500D03*
Y192000D03*
X1618940Y175780D03*
Y179280D03*
X1616500Y188500D03*
Y192000D03*
X1613500Y188500D03*
Y192000D03*
X1644930Y157200D03*
X1605760Y224590D03*
Y221090D03*
X1650473Y319500D03*
Y323000D03*
X1644300Y288050D03*
Y291550D03*
X1647300Y288050D03*
Y291550D03*
X1626217Y360391D03*
Y363891D03*
X1626100Y373700D03*
Y370200D03*
X1602700Y466900D03*
Y470400D03*
X1611175Y477667D03*
Y481167D03*
X1645256Y558000D03*
Y554500D03*
X1641756D03*
Y558000D03*
X1665000Y26250D03*
Y29750D03*
Y23250D03*
Y19750D03*
X1662600Y49000D03*
Y52500D03*
X1676400Y69500D03*
Y66000D03*
X1691800Y88700D03*
Y92200D03*
X1694800D03*
Y88700D03*
X1697800Y92200D03*
Y88700D03*
X1700800D03*
Y92200D03*
X1656000Y94500D03*
Y91000D03*
Y84500D03*
Y88000D03*
X1672500Y109800D03*
Y106300D03*
X1656000Y97500D03*
Y101000D03*
X1653849Y175788D03*
Y179288D03*
X1666701Y176011D03*
Y179511D03*
X1670081Y164849D03*
Y161349D03*
X1663681Y164849D03*
Y161349D03*
X1666881Y164849D03*
Y161349D03*
X1659500Y317250D03*
Y320750D03*
X1651500Y291650D03*
Y288150D03*
X1661248Y308711D03*
Y305211D03*
X1656000Y324250D03*
Y320750D03*
X1663280Y287691D03*
Y291191D03*
X1660080Y287691D03*
Y291191D03*
X1710101Y558628D03*
Y555128D03*
X1680000Y555900D03*
Y559400D03*
X1674000Y555500D03*
Y559000D03*
X1670000Y555500D03*
Y559000D03*
X1663000Y555400D03*
Y558900D03*
X1659500Y555400D03*
Y558900D03*
X1684000Y555900D03*
Y559400D03*
X1773100Y15200D03*
Y18700D03*
X1769250Y81070D03*
Y84570D03*
X1762300Y51600D03*
Y48100D03*
X1740300Y92100D03*
X1752060Y92110D03*
X1749810Y85620D03*
Y82120D03*
X1748550Y148138D03*
Y144638D03*
X1754825Y113100D03*
Y116600D03*
X1733403Y130212D03*
Y126712D03*
X1748425Y113100D03*
Y116600D03*
X1751625Y113100D03*
Y116600D03*
X1758025Y113100D03*
Y116600D03*
X1740300Y95600D03*
X1752060Y95610D03*
X1771525Y202827D03*
Y206327D03*
X1759497Y202827D03*
Y206327D03*
X1763497Y202827D03*
Y206327D03*
X1734100Y202400D03*
Y205900D03*
X1726000Y202750D03*
Y206250D03*
X1722500Y202750D03*
Y206250D03*
X1719000Y202750D03*
Y206250D03*
X1729500Y202750D03*
Y206250D03*
X1737600Y202400D03*
Y205900D03*
X1750589Y202571D03*
Y206071D03*
X1746589Y202571D03*
Y206071D03*
X1757220Y258433D03*
Y254933D03*
X1760420Y258433D03*
Y254933D03*
X1753900Y258400D03*
Y254900D03*
X1747500Y258400D03*
Y254900D03*
X1744300Y258400D03*
Y254900D03*
X1750700Y258400D03*
Y254900D03*
X1760000Y455130D03*
Y458630D03*
X1768500Y455130D03*
Y458630D03*
X1772500Y455130D03*
Y458630D03*
X1743500Y455130D03*
Y458630D03*
X1747500Y455130D03*
Y458630D03*
X1756000Y455130D03*
Y458630D03*
X1764900Y512800D03*
Y509300D03*
X1768400Y512800D03*
Y509300D03*
X1730950Y586000D03*
Y582500D03*
X1733950Y586004D03*
Y582504D03*
X1726850Y559000D03*
Y555500D03*
X1723000Y559000D03*
Y555500D03*
X1714101Y558628D03*
Y555128D03*
X1729950Y559000D03*
Y555500D03*
X1720550Y586250D03*
X1765000Y579000D03*
Y582500D03*
X1736097Y596859D03*
Y593359D03*
X1757057Y598292D03*
Y601792D03*
X1720550Y589750D03*
X1760157Y598243D03*
Y601743D03*
X1822400Y24700D03*
Y28200D03*
X1825500Y14250D03*
Y17750D03*
X1833236Y32980D03*
Y29480D03*
X1829236Y32980D03*
Y29480D03*
X1821250Y94500D03*
Y91000D03*
X1786700Y81450D03*
Y77950D03*
X1795377Y126231D03*
Y122731D03*
X1798377D03*
Y126231D03*
X1780623Y113769D03*
Y117269D03*
X1789300Y171000D03*
Y167500D03*
X1826100Y202927D03*
Y206427D03*
X1822100Y202927D03*
Y206427D03*
X1775525Y202827D03*
Y206327D03*
X1788300Y202527D03*
Y206027D03*
X1797200Y203127D03*
Y206627D03*
X1801200Y203127D03*
Y206627D03*
X1809600Y203027D03*
Y206527D03*
X1813600Y203027D03*
Y206527D03*
X1784300Y202527D03*
Y206027D03*
X1823000Y455130D03*
Y458630D03*
X1836000Y455130D03*
Y458630D03*
X1832000Y455130D03*
Y458630D03*
X1819000Y455130D03*
Y458630D03*
X1806500Y455130D03*
Y458630D03*
X1810500Y455130D03*
Y458630D03*
X1781500Y455130D03*
Y458630D03*
X1798000Y455130D03*
Y458630D03*
X1794000Y455130D03*
Y458630D03*
X1785500Y455130D03*
Y458630D03*
X1825000Y507200D03*
Y503700D03*
X1779300Y519100D03*
Y515600D03*
X1817900Y495600D03*
Y499100D03*
X1814400Y495600D03*
Y499100D03*
X1779300Y508100D03*
Y511600D03*
X1828600Y532500D03*
Y529000D03*
X1822052Y569001D03*
Y572501D03*
X1833052Y575501D03*
Y579001D03*
Y586001D03*
Y582501D03*
X1802400Y559100D03*
Y562600D03*
X1798400Y559100D03*
Y562600D03*
X1789188Y565224D03*
Y568724D03*
X1825552Y569001D03*
Y572501D03*
X1798250Y535300D03*
Y531800D03*
X1790500Y555600D03*
Y559100D03*
X1782700Y608400D03*
Y604900D03*
X1785700Y608400D03*
Y604900D03*
X1842000Y13750D03*
Y17250D03*
X1886465Y-15068D03*
Y-18568D03*
X1844835Y20168D03*
Y23668D03*
X1889575Y-15062D03*
Y-18562D03*
X1843236Y41480D03*
Y37980D03*
X1847236Y41480D03*
Y37980D03*
Y41480D03*
Y44980D03*
X1843236Y41480D03*
Y44980D03*
X1853600Y56800D03*
Y60300D03*
X1870817Y64594D03*
Y61094D03*
X1881290Y112580D03*
Y109080D03*
X1897500Y131500D03*
Y128000D03*
X1881000Y130750D03*
Y134250D03*
X1877500Y130750D03*
Y134250D03*
X1874939Y112567D03*
Y109067D03*
X1889790Y112580D03*
Y109080D03*
X1886290Y112580D03*
Y109080D03*
X1889913Y216937D03*
X1839000Y187250D03*
Y183750D03*
X1842000Y187250D03*
Y183750D03*
X1845000Y187250D03*
Y183750D03*
X1889913Y210437D03*
Y213937D03*
Y220437D03*
X1853000Y463500D03*
Y460000D03*
X1856000Y463500D03*
Y460000D03*
X1846000Y506000D03*
Y502500D03*
X1867500Y472200D03*
Y475700D03*
X1846000Y499500D03*
Y496000D03*
X1849000Y499500D03*
Y496000D03*
X1881293Y519486D03*
Y522986D03*
X1878272Y519465D03*
Y522965D03*
X1858090Y508600D03*
Y512100D03*
X1854890Y508600D03*
Y512100D03*
X1880704Y572718D03*
Y576218D03*
X1877704D03*
Y572718D03*
X1868704Y576218D03*
Y572718D03*
X1871704Y576218D03*
Y572718D03*
X1874704D03*
Y576218D03*
X1925135Y111900D03*
Y115400D03*
X1921620Y111900D03*
Y115400D03*
X1917953D03*
Y111900D03*
X1940900Y153400D03*
Y149900D03*
X1908100Y155900D03*
X1925535Y136078D03*
Y132578D03*
X1916300Y156300D03*
X1901000Y131500D03*
Y128000D03*
X1947686Y190522D03*
Y187022D03*
X1943482Y166512D03*
Y163012D03*
X1947646Y178328D03*
Y181828D03*
X1947662Y171828D03*
Y175328D03*
X1932700Y206835D03*
Y203335D03*
X1958902Y159545D03*
Y163045D03*
X1943776Y173012D03*
Y169512D03*
X1947686Y197022D03*
Y193522D03*
X1905800Y187550D03*
Y191050D03*
X1908100Y159400D03*
X1916300Y159800D03*
X1934800Y457700D03*
Y454200D03*
X1904000Y441630D03*
Y445130D03*
X1949940Y491950D03*
Y488450D03*
X1946350Y491950D03*
Y488450D03*
X1953440Y491950D03*
Y488450D03*
X1912800Y508250D03*
Y504750D03*
X1909800Y508250D03*
Y504750D03*
X1943100Y491920D03*
Y488420D03*
X1934720Y520400D03*
Y523900D03*
X1954120Y510380D03*
Y513880D03*
X1923260Y482920D03*
Y486420D03*
X1950620Y510380D03*
Y513880D03*
X1908859Y481161D03*
Y477661D03*
X1952970Y501030D03*
Y504530D03*
X1949800Y545850D03*
Y542350D03*
X1946800Y545900D03*
Y542400D03*
X1899550Y586365D03*
Y582865D03*
X1899700Y591100D03*
Y594600D03*
X1969100Y551100D03*
Y554600D03*
X1969800Y574600D03*
Y578100D03*
X1965700Y578200D03*
Y574700D03*
X1966100Y551000D03*
Y554500D03*
X1963200Y594600D03*
Y598100D03*
X1970000Y598200D03*
Y594700D03*
G54D31*
X72600Y-10500D03*
Y17500D03*
X73350Y518400D03*
Y490400D03*
X153666Y140388D03*
Y168388D03*
X705900Y347800D03*
Y375800D03*
X1317000Y70500D03*
Y42500D03*
X1296100Y136950D03*
Y108950D03*
X1316000Y209000D03*
Y181000D03*
X1407000Y105000D03*
Y133000D03*
X1422000Y63500D03*
Y91500D03*
X1440500Y63500D03*
Y91500D03*
X1451600Y583300D03*
Y555300D03*
X1475500Y581500D03*
Y553500D03*
X1496000Y581500D03*
Y553500D03*
X1519000Y581500D03*
Y553500D03*
X1559330Y577970D03*
Y549970D03*
X1540110Y577870D03*
Y549870D03*
G54D115*
X1523200Y432600D03*
X1518300D03*
G54D124*
X1651800Y92500D03*
Y87500D03*
X1624300Y90800D03*
X1651800Y97500D03*
G54D22*
X48700Y261300D03*
X29000D03*
X48700Y250260D03*
X29000D03*
G54D134*
X1697694Y151292D03*
X1690970Y103101D03*
X1676372Y138275D03*
X1692944Y144363D03*
X1691596Y162922D03*
G54D170*
X1899369Y237015D03*
G54D152*
X1830800Y513800D03*
Y503300D03*
X1834540Y513800D03*
X1838280D03*
Y503300D03*
G54D32*
X89100Y124700D03*
X85350Y116200D03*
X81600Y124700D03*
X72750Y354750D03*
X80250D03*
X76500Y363250D03*
X1526900Y257200D03*
X1519400D03*
X1523150Y248700D03*
X1472781Y330195D03*
X1476531Y338695D03*
X1480281Y330195D03*
X1774250Y75500D03*
X1716000Y79500D03*
X1719750Y88000D03*
X1723500Y79500D03*
X1781750Y75500D03*
X1778000Y84000D03*
X1882250Y463250D03*
X1874750D03*
X1878500Y454750D03*
X1940000Y532600D03*
X1947500D03*
X1943750Y541100D03*
G54D41*
X84781Y327900D03*
X86750Y332500D03*
X82813Y327900D03*
Y332500D03*
X84781D03*
X100431Y312900D03*
X102400Y317500D03*
X98463Y312900D03*
Y317500D03*
X100431D03*
X1613999Y23700D03*
X1615968Y28300D03*
X1612031Y23700D03*
Y28300D03*
X1613999D03*
G54D50*
X57745Y483757D03*
Y490757D03*
X412501Y275410D03*
Y268410D03*
X398048Y275441D03*
Y268441D03*
X405301Y275410D03*
Y268410D03*
X411001Y327910D03*
Y334910D03*
X418201Y327910D03*
Y334910D03*
X413001Y320410D03*
Y313410D03*
X377648Y315841D03*
Y322841D03*
X396348Y327941D03*
Y334941D03*
X403748Y327941D03*
Y334941D03*
X391401Y320410D03*
Y313410D03*
X384201Y320410D03*
Y313410D03*
X398601Y320410D03*
Y313410D03*
X405801Y320410D03*
Y313410D03*
X411501Y299410D03*
Y306410D03*
Y282410D03*
Y289410D03*
X382701Y282410D03*
Y289410D03*
X375501Y282410D03*
Y289410D03*
X368301Y282410D03*
Y289410D03*
X382701Y299410D03*
Y306410D03*
X389901Y282410D03*
Y289410D03*
Y299410D03*
Y306410D03*
X375501Y299410D03*
Y306410D03*
X368301Y299410D03*
Y306410D03*
X404301Y299410D03*
Y306410D03*
Y282410D03*
Y289410D03*
X397101Y299410D03*
Y306410D03*
Y282410D03*
Y289410D03*
X371148Y315841D03*
Y322841D03*
X434101Y275410D03*
Y268410D03*
X419701Y275410D03*
Y268410D03*
X426901Y275410D03*
Y268410D03*
X425401Y327910D03*
Y334910D03*
X432601Y327910D03*
Y334910D03*
X455648Y322341D03*
Y315341D03*
X420201Y320410D03*
Y313410D03*
X441801Y320291D03*
Y313291D03*
X434601Y320410D03*
Y313410D03*
X449001Y320410D03*
Y313410D03*
X427401Y320410D03*
Y313410D03*
X447648Y289341D03*
Y282341D03*
X425901Y299410D03*
Y306410D03*
Y282410D03*
Y289410D03*
X418701Y299410D03*
Y306410D03*
Y282410D03*
Y289410D03*
X440301Y299410D03*
Y306410D03*
X433101Y299410D03*
Y306410D03*
X447648Y299341D03*
Y306341D03*
X440301Y282410D03*
Y289410D03*
X433101Y282410D03*
Y289410D03*
X440194Y332291D03*
Y325291D03*
X655550Y7490D03*
Y14490D03*
X656170Y574690D03*
Y581690D03*
X721500Y60500D03*
Y53500D03*
X721900Y544100D03*
Y537100D03*
X1027256Y315841D03*
Y322841D03*
X1020756Y315841D03*
Y322841D03*
X1033809Y320410D03*
Y313410D03*
X1017909Y299410D03*
Y306410D03*
Y282410D03*
Y289410D03*
X1025109Y299410D03*
Y306410D03*
Y282410D03*
Y289410D03*
X1032309Y299410D03*
Y306410D03*
Y282410D03*
Y289410D03*
X1083709Y275410D03*
Y268410D03*
X1076509Y275410D03*
Y268410D03*
X1069309Y275410D03*
Y268410D03*
X1062109Y275410D03*
Y268410D03*
X1054909Y275410D03*
Y268410D03*
X1047656Y275441D03*
Y268441D03*
X1082209Y327910D03*
Y334910D03*
X1077009Y320410D03*
Y313410D03*
X1084209Y320410D03*
Y313410D03*
X1091409Y320410D03*
Y313410D03*
X1082709Y282410D03*
Y289410D03*
X1097256Y299341D03*
Y306341D03*
Y289341D03*
Y282341D03*
X1082709Y299410D03*
Y306410D03*
X1089909Y299410D03*
Y306410D03*
Y282410D03*
Y289410D03*
X1075009Y327910D03*
Y334910D03*
X1069809Y320410D03*
Y313410D03*
X1062609Y320410D03*
Y313410D03*
X1055409Y320410D03*
Y313410D03*
X1048209Y320410D03*
Y313410D03*
X1041009Y320410D03*
Y313410D03*
X1067809Y327910D03*
Y334910D03*
X1060609Y327910D03*
Y334910D03*
X1053356Y327941D03*
Y334941D03*
X1045956Y327941D03*
Y334941D03*
X1075509Y299410D03*
Y306410D03*
Y282410D03*
Y289410D03*
X1068309Y299410D03*
Y306410D03*
Y282410D03*
Y289410D03*
X1039509Y282410D03*
Y289410D03*
X1061109Y299410D03*
Y306410D03*
X1053909Y299410D03*
Y306410D03*
X1061109Y282410D03*
Y289410D03*
X1053909Y282410D03*
Y289410D03*
X1046709Y299410D03*
Y306410D03*
Y282410D03*
Y289410D03*
X1039509Y299410D03*
Y306410D03*
X1088900Y332800D03*
Y325800D03*
X1105256Y322341D03*
Y315341D03*
X1098609Y320410D03*
Y313410D03*
X1382000Y119500D03*
Y112500D03*
X1384500Y524500D03*
X1376500D03*
X1365413Y524149D03*
X1384500Y531500D03*
X1376500D03*
X1365413Y531149D03*
X1521668Y602139D03*
Y609139D03*
X1528168Y602139D03*
Y609139D03*
X1514668Y602139D03*
Y609139D03*
X1480200Y601099D03*
Y608099D03*
X1487200Y601099D03*
Y608099D03*
X1493700Y601139D03*
Y608139D03*
X1601106Y459700D03*
Y452700D03*
X1607614Y459696D03*
Y452696D03*
X1621900Y487300D03*
Y480300D03*
X1628500Y487000D03*
Y480000D03*
X1803495Y66060D03*
Y73060D03*
X1809995Y66060D03*
Y73060D03*
X1858769Y55803D03*
Y62803D03*
X1871500Y128000D03*
Y135000D03*
X1902340Y105391D03*
Y112391D03*
X1910500Y112000D03*
Y119000D03*
G54D161*
X1856950Y488500D03*
Y491650D03*
X1864950D03*
Y488500D03*
X1919780Y236286D03*
Y239436D03*
X1927780D03*
Y236286D03*
X1911755Y228753D03*
Y231903D03*
X1919755D03*
Y228753D03*
G54D125*
X1646200Y92500D03*
Y87500D03*
X1618700Y90800D03*
X1646200Y97500D03*
G54D107*
X1453327Y306678D03*
X1456477D03*
X1491925Y270500D03*
X1495075D03*
X1515050Y403500D03*
X1518200D03*
X1513925Y415175D03*
X1517075D03*
X1503925Y427100D03*
X1507075D03*
X1507625Y437225D03*
X1510775D03*
X1530350Y411300D03*
X1533500D03*
X1544225Y433200D03*
X1547375D03*
G54D143*
X1741189Y165669D03*
X1745689D03*
X1750189D03*
X1736689D03*
X1732189D03*
X1727689D03*
X1723189D03*
X1718689D03*
X1723189Y173125D03*
X1718689D03*
X1727689D03*
X1732189D03*
X1736689D03*
X1741189D03*
X1745689D03*
X1750189D03*
X1721808Y601405D03*
X1781800Y588450D03*
G54D14*
X-13780Y598560D03*
X-3937Y-43307D03*
Y646063D03*
X1956693Y-43307D03*
Y646063D03*
G54D23*
X48700Y255780D03*
X29000D03*
G54D116*
X1508500Y432500D03*
X1513400D03*
G54D126*
X1624249Y156438D03*
X1680200Y165650D03*
X1780103Y69879D03*
X1833650Y98250D03*
G54D51*
X47500Y507100D03*
X1471900Y176700D03*
X1599530Y205480D03*
X1627200Y169500D03*
X1669700Y85000D03*
X1745600Y87950D03*
X1759108Y132250D03*
Y127750D03*
Y141250D03*
Y136750D03*
X1767670Y132250D03*
Y127750D03*
Y141250D03*
Y136750D03*
X1759108Y145798D03*
X1767622D03*
X1725300Y198700D03*
X1891900Y225100D03*
G54D171*
X1912342Y481228D03*
G54D135*
X1703100Y135246D03*
G54D162*
X1923379Y78770D03*
X1918379D03*
X1928379D03*
X1933379D03*
Y105370D03*
X1918379D03*
X1923379D03*
X1928379D03*
G54D60*
X601747Y170876D03*
G54D42*
X86750Y328000D03*
X102400Y313000D03*
X1615968Y23800D03*
G54D153*
X1807521Y587899D03*
X1813505D03*
G54D144*
X1741189Y162269D03*
X1745689D03*
X1750189D03*
X1736689D03*
X1732189D03*
X1727689D03*
X1723189D03*
X1718689D03*
X1723189Y169725D03*
X1718689D03*
X1727689D03*
X1732189D03*
X1736689D03*
X1741189D03*
X1745689D03*
X1750189D03*
X1721808Y598005D03*
X1781800Y585050D03*
G54D33*
X57069Y147990D03*
X62560Y148940D03*
X69500Y388050D03*
X66809Y416405D03*
X60279Y415455D03*
X134000Y461350D03*
X139300Y453450D03*
X139776Y437704D03*
X121800Y462300D03*
X126700Y454400D03*
X130000Y446600D03*
X132100Y438654D03*
X427158Y122970D03*
X576115Y265575D03*
X1349730Y344550D03*
X1425443Y189960D03*
X1443930Y309840D03*
X1442169Y450250D03*
X1442646Y440250D03*
X1458100Y439300D03*
X1435500Y462230D03*
X1448000Y463180D03*
X1466800Y156800D03*
X1525567Y241237D03*
X1470768Y446550D03*
X1484200Y492420D03*
X1474488Y493370D03*
X1479303Y495800D03*
X1471829Y498585D03*
X1479300Y501438D03*
X1487200Y502388D03*
X1475483Y488050D03*
X1586771Y500628D03*
X1576075Y499693D03*
X1587815Y493308D03*
X1598477Y118900D03*
X1604603Y140607D03*
X1602600Y135856D03*
X1595851Y499678D03*
X1670733Y140300D03*
X1677740Y152650D03*
X1673132Y154625D03*
X1706296Y158650D03*
X1747300Y141050D03*
X1747654Y155850D03*
X1740779Y133050D03*
X1775900Y588400D03*
X1901671Y542000D03*
X1908295Y541050D03*
X1915085Y540100D03*
G54D15*
X16117Y-43892D03*
X8543Y636173D03*
X177070Y121250D03*
X237330Y408960D03*
X475000Y122500D03*
X539500Y478000D03*
X735000Y392500D03*
X872000Y111000D03*
X1215624Y133363D03*
X1225000Y487600D03*
X1925000Y62000D03*
X1926693Y646063D03*
G54D117*
X1467570Y481702D03*
X1473246Y482312D03*
G54D24*
X17300Y455330D03*
X1839390Y64536D03*
G54D108*
X1431595Y422663D03*
G54D172*
X1912342Y477628D03*
G54D118*
X1552100Y86000D03*
Y94000D03*
X1560900Y90000D03*
G54D154*
X1804450Y597938D03*
Y594001D03*
Y595970D03*
Y592032D03*
Y590064D03*
G54D70*
X622421Y126575D03*
G54D25*
X17300Y450210D03*
X1839390Y59416D03*
G54D136*
X1673296Y115832D03*
G54D145*
X1741419Y157650D03*
G54D34*
X75500Y279500D03*
Y274000D03*
X51200Y496250D03*
Y490750D03*
X194600Y242848D03*
Y248348D03*
Y238348D03*
Y232848D03*
Y274000D03*
Y279500D03*
Y303000D03*
Y308500D03*
Y335730D03*
Y341230D03*
Y363600D03*
Y369100D03*
X454148Y299091D03*
Y304591D03*
Y288341D03*
Y282841D03*
X714950Y12050D03*
Y17550D03*
X723135Y4952D03*
Y-548D03*
X680600Y42300D03*
Y47800D03*
X667500Y294800D03*
Y289300D03*
X679800Y528500D03*
Y534000D03*
X717203Y588502D03*
X712101Y588262D03*
X717203Y594002D03*
X712101Y593762D03*
X729335Y4952D03*
Y-548D03*
X729350Y506700D03*
Y501200D03*
X844500Y238480D03*
Y232980D03*
Y242980D03*
Y248480D03*
Y271500D03*
Y277000D03*
Y303200D03*
Y308700D03*
Y334750D03*
Y340250D03*
Y366300D03*
Y371800D03*
X1103756Y299091D03*
Y304591D03*
Y288341D03*
Y282841D03*
X1338500Y101500D03*
Y107000D03*
X1335900Y512800D03*
Y518300D03*
X1304500Y619000D03*
Y613500D03*
X1528100Y426600D03*
Y432100D03*
X1472500Y538250D03*
Y543750D03*
X1477500Y538250D03*
Y543750D03*
X1499400Y536000D03*
Y541500D03*
X1514600Y536000D03*
Y541500D03*
X1509600Y536000D03*
Y541500D03*
X1504300Y536000D03*
Y541500D03*
X1585064Y122049D03*
Y116549D03*
X1576187Y131439D03*
Y136939D03*
X1583500Y127000D03*
Y132500D03*
X1580364Y116549D03*
Y122049D03*
X1580000Y399350D03*
X1575300D03*
X1580000Y404850D03*
X1579814Y434014D03*
Y439514D03*
X1575300Y404850D03*
X1575500Y431000D03*
Y425500D03*
X1571584Y561509D03*
Y556009D03*
X1576520Y561500D03*
Y556000D03*
X1632849Y134888D03*
Y140388D03*
X1609300Y403200D03*
X1604000Y403250D03*
X1590700Y465250D03*
Y459750D03*
X1608000Y464546D03*
X1595500Y465250D03*
Y459750D03*
X1590600Y422250D03*
Y416750D03*
X1600000Y422250D03*
Y416750D03*
X1609300Y408700D03*
X1604000Y408750D03*
X1595300Y422250D03*
Y416750D03*
X1608000Y470046D03*
X1674031Y166649D03*
Y161149D03*
X1828090Y156630D03*
X1833650Y156830D03*
X1828090Y162130D03*
X1833650Y162330D03*
X1869490Y112980D03*
Y107480D03*
X1895137Y105252D03*
Y110752D03*
X1843600Y158200D03*
Y163700D03*
X1901400Y156850D03*
Y151350D03*
X1912100Y156400D03*
X1910500Y185750D03*
Y191250D03*
X1912100Y161900D03*
G54D43*
X68418Y325500D03*
X65859D03*
X68418Y332500D03*
X63300D03*
X65859D03*
X63300Y325500D03*
X663000Y507500D03*
Y500500D03*
X668118D03*
X665559Y507500D03*
X668118D03*
X1231394Y116162D03*
X1233953D03*
X1228835D03*
Y109162D03*
X1231394D03*
X1233953D03*
X1241772Y109188D03*
X1239213D03*
X1244331D03*
Y116188D03*
X1241772D03*
X1239213D03*
X1306320Y28900D03*
X1303760D03*
X1301200D03*
X1306320Y35900D03*
X1301200D03*
X1303760D03*
X1596082Y219000D03*
X1598641D03*
X1596082Y212000D03*
X1601200D03*
X1598641D03*
X1601200Y219000D03*
X1759067Y586743D03*
X1753949D03*
X1756508Y593743D03*
X1759067D03*
X1753949D03*
X1795436Y131481D03*
X1792877Y138481D03*
X1790318Y131481D03*
X1795436Y138481D03*
X1790318D03*
X1789300Y506600D03*
X1784182Y513600D03*
X1786741Y506600D03*
X1789300Y513600D03*
X1784182Y506600D03*
X1812800Y510600D03*
X1817918Y503600D03*
X1815359Y510600D03*
X1812800Y503600D03*
X1817918Y510600D03*
X1804541D03*
X1807100D03*
X1804541Y503600D03*
X1807100D03*
X1801982D03*
Y510600D03*
X1894968Y213827D03*
Y220827D03*
X1897527D03*
X1900086Y213827D03*
X1936369Y190204D03*
X1938928D03*
X1936369Y183204D03*
X1941487D03*
X1938928D03*
X1941487Y190204D03*
X1900086Y220827D03*
X1943518Y517500D03*
X1938400Y524500D03*
X1940959D03*
X1938400Y517500D03*
X1943518Y524500D03*
X1942722Y505100D03*
X1945281Y498100D03*
X1947840D03*
Y505100D03*
X1942722Y498100D03*
X1951439Y519250D03*
X1948880D03*
X1951439Y526250D03*
X1948880D03*
X1953998D03*
Y519250D03*
X1931059Y546500D03*
X1928500D03*
X1931059Y553500D03*
X1925941D03*
X1928500D03*
X1925941Y546500D03*
X1931059Y599000D03*
X1928500Y606000D03*
X1925941D03*
Y599000D03*
X1931059Y606000D03*
X1967040Y506010D03*
X1961922Y513010D03*
X1964481Y506010D03*
X1967040Y513010D03*
X1961922Y506010D03*
X1969500Y583300D03*
X1966941D03*
X1964382D03*
X1964882Y570000D03*
X1970000Y563000D03*
X1967441D03*
X1970000Y570000D03*
X1964882Y563000D03*
X1964382Y590300D03*
X1969500D03*
G54D52*
X116927Y22133D03*
Y4023D03*
X120273Y22133D03*
X126966D03*
X133659D03*
X143699D03*
X150392D03*
X157084D03*
X163777D03*
X123620Y4023D03*
X130313D03*
X137006D03*
X147045D03*
X153738D03*
X160431D03*
X167124D03*
X137006Y22133D03*
X140352D03*
X143699Y4023D03*
X140352D03*
X120273D03*
X167124Y22133D03*
X150392Y4023D03*
X147045Y22133D03*
X126966Y4023D03*
X123620Y22133D03*
X157084Y4023D03*
X153738Y22133D03*
X133659Y4023D03*
X163777D03*
X160431Y22133D03*
X130313D03*
X116927Y59933D03*
Y41823D03*
X120273Y59933D03*
X126966D03*
X133659D03*
X143699D03*
X150392D03*
X157084D03*
X163777D03*
X123620Y41823D03*
X130313D03*
X137006D03*
X147045D03*
X153738D03*
X160431D03*
X167124D03*
X137006Y59933D03*
X140352D03*
X143699Y41823D03*
X140352D03*
X120273D03*
X167124Y59933D03*
X150392Y41823D03*
X147045Y59933D03*
X126966Y41823D03*
X123620Y59933D03*
X157084Y41823D03*
X153738Y59933D03*
X133659Y41823D03*
X163777D03*
X160431Y59933D03*
X130313D03*
X116927Y97733D03*
Y79623D03*
X120273Y97733D03*
X126966D03*
X133659D03*
X143699D03*
X150392D03*
X157084D03*
X163777D03*
X123620Y79623D03*
X130313D03*
X137006D03*
X147045D03*
X153738D03*
X160431D03*
X167124D03*
X137006Y97733D03*
X140352D03*
X143699Y79623D03*
X140352D03*
X120273D03*
X167124Y97733D03*
X150392Y79623D03*
X147045Y97733D03*
X126966Y79623D03*
X123620Y97733D03*
X157084Y79623D03*
X153738Y97733D03*
X133659Y79623D03*
X163777D03*
X160431Y97733D03*
X130313D03*
X167124Y505024D03*
X163777D03*
X160431D03*
X157084D03*
X153738D03*
X150392D03*
X147045D03*
X143699D03*
X140352D03*
X137006D03*
X133659D03*
X130313D03*
X126966D03*
X123620D03*
X120273D03*
X116927D03*
X167124Y523134D03*
X163777D03*
X160431D03*
X157084D03*
X153738D03*
X150392D03*
X147045D03*
X143699D03*
X140352D03*
X137006D03*
X133659D03*
X130313D03*
X126966D03*
X123620D03*
X120273D03*
X116927D03*
X167124Y580624D03*
X163777D03*
X160431D03*
X157084D03*
X153738D03*
X150392D03*
X147045D03*
X143699D03*
X140352D03*
X137006D03*
X133659D03*
X130313D03*
X126966D03*
X123620D03*
X120273D03*
X116927D03*
X167124Y542824D03*
X163777D03*
X160431D03*
X157084D03*
X153738D03*
X150392D03*
X147045D03*
X143699D03*
X140352D03*
X137006D03*
X133659D03*
X130313D03*
X126966D03*
X123620D03*
X120273D03*
X116927D03*
X167124Y560934D03*
X163777D03*
X160431D03*
X157084D03*
X153738D03*
X150392D03*
X147045D03*
X143699D03*
X140352D03*
X137006D03*
X133659D03*
X130313D03*
X126966D03*
X123620D03*
X120273D03*
X116927D03*
X167124Y598734D03*
X163777D03*
X160431D03*
X157084D03*
X153738D03*
X150392D03*
X147045D03*
X143699D03*
X140352D03*
X137006D03*
X133659D03*
X130313D03*
X126966D03*
X123620D03*
X120273D03*
X116927D03*
X170470Y22133D03*
X180510D03*
X187203D03*
X193896D03*
X200588D03*
X207281D03*
X217321D03*
X224014D03*
X230707D03*
X173817Y4023D03*
X183856D03*
X190549D03*
X197242D03*
X203935D03*
X210628D03*
X220667D03*
X227360D03*
X217321D03*
X213974D03*
X180510D03*
X177163D03*
X210628Y22133D03*
X213974D03*
X173817D03*
X177163D03*
X170470Y4023D03*
X224014D03*
X220667Y22133D03*
X200588Y4023D03*
X197242Y22133D03*
X230707Y4023D03*
X227360Y22133D03*
X207281Y4023D03*
X203935Y22133D03*
X187203Y4023D03*
X183856Y22133D03*
X193896Y4023D03*
X190549Y22133D03*
X170470Y59933D03*
X180510D03*
X187203D03*
X193896D03*
X200588D03*
X207281D03*
X217321D03*
X224014D03*
X230707D03*
X173817Y41823D03*
X183856D03*
X190549D03*
X197242D03*
X203935D03*
X210628D03*
X220667D03*
X227360D03*
X217321D03*
X213974D03*
X180510D03*
X177163D03*
X210628Y59933D03*
X213974D03*
X173817D03*
X177163D03*
X170470Y41823D03*
X224014D03*
X220667Y59933D03*
X200588Y41823D03*
X197242Y59933D03*
X230707Y41823D03*
X227360Y59933D03*
X207281Y41823D03*
X203935Y59933D03*
X187203Y41823D03*
X183856Y59933D03*
X193896Y41823D03*
X190549Y59933D03*
X170470Y97733D03*
X180510D03*
X187203D03*
X193896D03*
X200588D03*
X207281D03*
X217321D03*
X224014D03*
X230707D03*
X173817Y79623D03*
X183856D03*
X190549D03*
X197242D03*
X203935D03*
X210628D03*
X220667D03*
X227360D03*
X217321D03*
X213974D03*
X180510D03*
X177163D03*
X210628Y97733D03*
X213974D03*
X173817D03*
X177163D03*
X170470Y79623D03*
X224014D03*
X220667Y97733D03*
X200588Y79623D03*
X197242Y97733D03*
X230707Y79623D03*
X227360Y97733D03*
X207281Y79623D03*
X203935Y97733D03*
X187203Y79623D03*
X183856Y97733D03*
X193896Y79623D03*
X190549Y97733D03*
X230707Y505024D03*
X227360D03*
X224014D03*
X220667D03*
X217321D03*
X213974D03*
X210628D03*
X207281D03*
X203935D03*
X200588D03*
X197242D03*
X193896D03*
X190549D03*
X187203D03*
X183856D03*
X180510D03*
X177163D03*
X173817D03*
X170470D03*
X230707Y523134D03*
X227360D03*
X224014D03*
X220667D03*
X217321D03*
X213974D03*
X210628D03*
X207281D03*
X203935D03*
X200588D03*
X197242D03*
X193896D03*
X190549D03*
X187203D03*
X183856D03*
X180510D03*
X177163D03*
X173817D03*
X170470D03*
X230707Y580624D03*
X227360D03*
X224014D03*
X220667D03*
X217321D03*
X213974D03*
X210628D03*
X207281D03*
X203935D03*
X200588D03*
X197242D03*
X193896D03*
X190549D03*
X187203D03*
X183856D03*
X180510D03*
X177163D03*
X173817D03*
X170470D03*
X230707Y542824D03*
X227360D03*
X224014D03*
X220667D03*
X217321D03*
X213974D03*
X210628D03*
X207281D03*
X203935D03*
X200588D03*
X197242D03*
X193896D03*
X190549D03*
X187203D03*
X183856D03*
X180510D03*
X177163D03*
X173817D03*
X170470D03*
X230707Y560934D03*
X227360D03*
X224014D03*
X220667D03*
X217321D03*
X213974D03*
X210628D03*
X207281D03*
X203935D03*
X200588D03*
X197242D03*
X193896D03*
X190549D03*
X187203D03*
X183856D03*
X180510D03*
X177163D03*
X173817D03*
X170470D03*
X230707Y598734D03*
X227360D03*
X224014D03*
X220667D03*
X217321D03*
X213974D03*
X210628D03*
X207281D03*
X203935D03*
X200588D03*
X197242D03*
X193896D03*
X190549D03*
X187203D03*
X183856D03*
X180510D03*
X177163D03*
X173817D03*
X170470D03*
X237399Y22133D03*
X244092D03*
X254132D03*
X260825D03*
X267518D03*
X274210D03*
X280903D03*
X290943D03*
X234053Y4023D03*
X240746D03*
X247439D03*
X257478D03*
X264171D03*
X270864D03*
X277557D03*
X284250D03*
X290943D03*
X287596D03*
X254132D03*
X250785D03*
X284250Y22133D03*
X287596D03*
X247439D03*
X250785D03*
X260825Y4023D03*
X257478Y22133D03*
X237399Y4023D03*
X234053Y22133D03*
X267518Y4023D03*
X264171Y22133D03*
X244092Y4023D03*
X240746Y22133D03*
X274210Y4023D03*
X270864Y22133D03*
X280903Y4023D03*
X277557Y22133D03*
X237399Y59933D03*
X244092D03*
X254132D03*
X260825D03*
X267518D03*
X274210D03*
X280903D03*
X290943D03*
X234053Y41823D03*
X240746D03*
X247439D03*
X257478D03*
X264171D03*
X270864D03*
X277557D03*
X284250D03*
X290943D03*
X287596D03*
X254132D03*
X250785D03*
X284250Y59933D03*
X287596D03*
X247439D03*
X250785D03*
X260825Y41823D03*
X257478Y59933D03*
X237399Y41823D03*
X234053Y59933D03*
X267518Y41823D03*
X264171Y59933D03*
X244092Y41823D03*
X240746Y59933D03*
X274210Y41823D03*
X270864Y59933D03*
X280903Y41823D03*
X277557Y59933D03*
X237399Y97733D03*
X244092D03*
X254132D03*
X260825D03*
X267518D03*
X274210D03*
X280903D03*
X290943D03*
X234053Y79623D03*
X240746D03*
X247439D03*
X257478D03*
X264171D03*
X270864D03*
X277557D03*
X284250D03*
X290943D03*
X287596D03*
X254132D03*
X250785D03*
X284250Y97733D03*
X287596D03*
X247439D03*
X250785D03*
X260825Y79623D03*
X257478Y97733D03*
X237399Y79623D03*
X234053Y97733D03*
X267518Y79623D03*
X264171Y97733D03*
X244092Y79623D03*
X240746Y97733D03*
X274210Y79623D03*
X270864Y97733D03*
X280903Y79623D03*
X277557Y97733D03*
X290943Y505024D03*
X287596D03*
X284250D03*
X280903D03*
X277557D03*
X274210D03*
X270864D03*
X267518D03*
X264171D03*
X260825D03*
X257478D03*
X254132D03*
X250785D03*
X247439D03*
X244092D03*
X240746D03*
X237399D03*
X234053D03*
X290943Y523134D03*
X287596D03*
X284250D03*
X280903D03*
X277557D03*
X274210D03*
X270864D03*
X267518D03*
X264171D03*
X260825D03*
X257478D03*
X254132D03*
X250785D03*
X247439D03*
X244092D03*
X240746D03*
X237399D03*
X234053D03*
X290943Y580624D03*
X287596D03*
X284250D03*
X280903D03*
X277557D03*
X274210D03*
X270864D03*
X267518D03*
X264171D03*
X260825D03*
X257478D03*
X254132D03*
X250785D03*
X247439D03*
X244092D03*
X240746D03*
X237399D03*
X234053D03*
X290943Y542824D03*
X287596D03*
X284250D03*
X280903D03*
X277557D03*
X274210D03*
X270864D03*
X267518D03*
X264171D03*
X260825D03*
X257478D03*
X254132D03*
X250785D03*
X247439D03*
X244092D03*
X240746D03*
X237399D03*
X234053D03*
X290943Y560934D03*
X287596D03*
X284250D03*
X280903D03*
X277557D03*
X274210D03*
X270864D03*
X267518D03*
X264171D03*
X260825D03*
X257478D03*
X254132D03*
X250785D03*
X247439D03*
X244092D03*
X240746D03*
X237399D03*
X234053D03*
X290943Y598734D03*
X287596D03*
X284250D03*
X280903D03*
X277557D03*
X274210D03*
X270864D03*
X267518D03*
X264171D03*
X260825D03*
X257478D03*
X254132D03*
X250785D03*
X247439D03*
X244092D03*
X240746D03*
X237399D03*
X234053D03*
X341140Y4023D03*
X351179D03*
X311021Y22133D03*
X317714D03*
X327754D03*
X337793D03*
X347833D03*
X314368Y4023D03*
X321061D03*
X331100D03*
X297636Y22133D03*
X304329D03*
X294289Y4023D03*
X300982D03*
X307675D03*
X317714D03*
X307675Y22133D03*
X311021Y4023D03*
X314368Y22133D03*
X297636Y4023D03*
X294289Y22133D03*
X304329Y4023D03*
X300982Y22133D03*
X324407Y4023D03*
Y22133D03*
X327754Y4023D03*
X321061Y22133D03*
X334447D03*
X341140D03*
X337793Y4023D03*
X344486Y22133D03*
Y4023D03*
X347833D03*
X351179Y22133D03*
X354525Y4023D03*
X331100Y22133D03*
X334447Y4023D03*
X354525Y22133D03*
X341140Y41823D03*
X351179D03*
X311021Y59933D03*
X317714D03*
X327754D03*
X337793D03*
X347833D03*
X314368Y41823D03*
X321061D03*
X331100D03*
X297636Y59933D03*
X304329D03*
X294289Y41823D03*
X300982D03*
X307675D03*
X317714D03*
X307675Y59933D03*
X311021Y41823D03*
X314368Y59933D03*
X297636Y41823D03*
X294289Y59933D03*
X304329Y41823D03*
X300982Y59933D03*
X324407Y41823D03*
Y59933D03*
X327754Y41823D03*
X321061Y59933D03*
X334447D03*
X341140D03*
X337793Y41823D03*
X344486Y59933D03*
Y41823D03*
X347833D03*
X351179Y59933D03*
X354525Y41823D03*
X331100Y59933D03*
X334447Y41823D03*
X354525Y59933D03*
X341140Y79623D03*
X351179D03*
X311021Y97733D03*
X317714D03*
X327754D03*
X337793D03*
X347833D03*
X314368Y79623D03*
X321061D03*
X331100D03*
X297636Y97733D03*
X304329D03*
X294289Y79623D03*
X300982D03*
X307675D03*
X317714D03*
X307675Y97733D03*
X311021Y79623D03*
X314368Y97733D03*
X297636Y79623D03*
X294289Y97733D03*
X304329Y79623D03*
X300982Y97733D03*
X324407Y79623D03*
Y97733D03*
X327754Y79623D03*
X321061Y97733D03*
X334447D03*
X341140D03*
X337793Y79623D03*
X344486Y97733D03*
Y79623D03*
X347833D03*
X351179Y97733D03*
X354525Y79623D03*
X331100Y97733D03*
X334447Y79623D03*
X354525Y97733D03*
Y505024D03*
X351179D03*
X347833D03*
X344486D03*
X341140D03*
X337793D03*
X334447D03*
X331100D03*
X327754D03*
X324407D03*
X321061D03*
X317714D03*
X314368D03*
X311021D03*
X307675D03*
X304329D03*
X300982D03*
X297636D03*
X294289D03*
X354525Y523134D03*
X351179D03*
X347833D03*
X344486D03*
X341140D03*
X337793D03*
X334447D03*
X331100D03*
X327754D03*
X324407D03*
X321061D03*
X317714D03*
X314368D03*
X311021D03*
X307675D03*
X304329D03*
X300982D03*
X297636D03*
X294289D03*
X354525Y580624D03*
X351179D03*
X347833D03*
X344486D03*
X341140D03*
X337793D03*
X334447D03*
X331100D03*
X327754D03*
X324407D03*
X321061D03*
X317714D03*
X314368D03*
X311021D03*
X307675D03*
X304329D03*
X300982D03*
X297636D03*
X294289D03*
X354525Y542824D03*
X351179D03*
X347833D03*
X344486D03*
X341140D03*
X337793D03*
X334447D03*
X331100D03*
X327754D03*
X324407D03*
X321061D03*
X317714D03*
X314368D03*
X311021D03*
X307675D03*
X304329D03*
X300982D03*
X297636D03*
X294289D03*
X354525Y560934D03*
X351179D03*
X347833D03*
X344486D03*
X341140D03*
X337793D03*
X334447D03*
X331100D03*
X327754D03*
X324407D03*
X321061D03*
X317714D03*
X314368D03*
X311021D03*
X307675D03*
X304329D03*
X300982D03*
X297636D03*
X294289D03*
X354525Y598734D03*
X351179D03*
X347833D03*
X344486D03*
X341140D03*
X337793D03*
X334447D03*
X331100D03*
X327754D03*
X324407D03*
X321061D03*
X317714D03*
X314368D03*
X311021D03*
X307675D03*
X304329D03*
X300982D03*
X297636D03*
X294289D03*
X371258Y22133D03*
Y4023D03*
X357872D03*
X367911D03*
X398029D03*
X408069D03*
X357872Y22133D03*
X367911D03*
X401376D03*
X411415D03*
X414762D03*
X411415Y4023D03*
X394683D03*
Y22133D03*
X361218Y4023D03*
X364565D03*
X361218Y22133D03*
X364565D03*
X401376Y4023D03*
X404722Y22133D03*
X408069D03*
X414762Y4023D03*
X404722D03*
X398029Y22133D03*
X371258Y59933D03*
Y41823D03*
X357872D03*
X367911D03*
X398029D03*
X408069D03*
X357872Y59933D03*
X367911D03*
X401376D03*
X411415D03*
X414762D03*
X411415Y41823D03*
X394683D03*
Y59933D03*
X361218Y41823D03*
X364565D03*
X361218Y59933D03*
X364565D03*
X401376Y41823D03*
X404722Y59933D03*
X408069D03*
X414762Y41823D03*
X404722D03*
X398029Y59933D03*
X371258Y97733D03*
Y79623D03*
X357872D03*
X367911D03*
X398029D03*
X408069D03*
X357872Y97733D03*
X367911D03*
X401376D03*
X411415D03*
X414762D03*
X411415Y79623D03*
X394683D03*
Y97733D03*
X361218Y79623D03*
X364565D03*
X361218Y97733D03*
X364565D03*
X401376Y79623D03*
X404722Y97733D03*
X408069D03*
X414762Y79623D03*
X404722D03*
X398029Y97733D03*
X414762Y505024D03*
X411415D03*
X408069D03*
X404722D03*
X401376D03*
X398029D03*
X394683D03*
X371258D03*
X367911D03*
X364565D03*
X361218D03*
X357872D03*
X414762Y523134D03*
X411415D03*
X408069D03*
X404722D03*
X401376D03*
X398029D03*
X394683D03*
X371258D03*
X367911D03*
X364565D03*
X361218D03*
X357872D03*
X414762Y580624D03*
X411415D03*
X408069D03*
X404722D03*
X401376D03*
X398029D03*
X394683D03*
X371258D03*
X367911D03*
X364565D03*
X361218D03*
X357872D03*
X414762Y542824D03*
X411415D03*
X408069D03*
X404722D03*
X401376D03*
X398029D03*
X394683D03*
X371258D03*
X367911D03*
X364565D03*
X361218D03*
X357872D03*
X414762Y560934D03*
X411415D03*
X408069D03*
X404722D03*
X401376D03*
X398029D03*
X394683D03*
X371258D03*
X367911D03*
X364565D03*
X361218D03*
X357872D03*
X414762Y598734D03*
X411415D03*
X408069D03*
X404722D03*
X401376D03*
X398029D03*
X394683D03*
X371258D03*
X367911D03*
X364565D03*
X361218D03*
X357872D03*
X418108Y4023D03*
X424801D03*
X431494D03*
X418108Y22133D03*
X428147D03*
X434840D03*
X441533D03*
Y4023D03*
X448226Y22133D03*
X454919D03*
X461612D03*
X471651D03*
X478344D03*
X451573Y4023D03*
X458266D03*
X464958D03*
X474998D03*
X471651D03*
X468305D03*
X464958Y22133D03*
X468305D03*
X421455Y4023D03*
X448226D03*
X444880D03*
Y22133D03*
X431494D03*
X438187D03*
X424801D03*
X478344Y4023D03*
X474998Y22133D03*
X454919Y4023D03*
X451573Y22133D03*
X461612Y4023D03*
X458266Y22133D03*
X438187Y4023D03*
X434840D03*
X421455Y22133D03*
X428147Y4023D03*
X418108Y41823D03*
X424801D03*
X431494D03*
X418108Y59933D03*
X428147D03*
X434840D03*
X441533D03*
Y41823D03*
X448226Y59933D03*
X454919D03*
X461612D03*
X471651D03*
X478344D03*
X451573Y41823D03*
X458266D03*
X464958D03*
X474998D03*
X471651D03*
X468305D03*
X464958Y59933D03*
X468305D03*
X421455Y41823D03*
X448226D03*
X444880D03*
Y59933D03*
X431494D03*
X438187D03*
X424801D03*
X478344Y41823D03*
X474998Y59933D03*
X454919Y41823D03*
X451573Y59933D03*
X461612Y41823D03*
X458266Y59933D03*
X438187Y41823D03*
X434840D03*
X421455Y59933D03*
X428147Y41823D03*
X418108Y79623D03*
X424801D03*
X431494D03*
X418108Y97733D03*
X428147D03*
X434840D03*
X441533D03*
Y79623D03*
X448226Y97733D03*
X454919D03*
X461612D03*
X471651D03*
X478344D03*
X451573Y79623D03*
X458266D03*
X464958D03*
X474998D03*
X471651D03*
X468305D03*
X464958Y97733D03*
X468305D03*
X421455Y79623D03*
X448226D03*
X444880D03*
Y97733D03*
X431494D03*
X438187D03*
X424801D03*
X478344Y79623D03*
X474998Y97733D03*
X454919Y79623D03*
X451573Y97733D03*
X461612Y79623D03*
X458266Y97733D03*
X438187Y79623D03*
X434840D03*
X421455Y97733D03*
X428147Y79623D03*
X478344Y505024D03*
X474998D03*
X471651D03*
X468305D03*
X464958D03*
X461612D03*
X458266D03*
X454919D03*
X451573D03*
X448226D03*
X444880D03*
X441533D03*
X438187D03*
X434840D03*
X431494D03*
X428147D03*
X424801D03*
X421455D03*
X418108D03*
X478344Y523134D03*
X474998D03*
X471651D03*
X468305D03*
X464958D03*
X461612D03*
X458266D03*
X454919D03*
X451573D03*
X448226D03*
X444880D03*
X441533D03*
X438187D03*
X434840D03*
X431494D03*
X428147D03*
X424801D03*
X421455D03*
X418108D03*
X478344Y580624D03*
X474998D03*
X471651D03*
X468305D03*
X464958D03*
X461612D03*
X458266D03*
X454919D03*
X451573D03*
X448226D03*
X444880D03*
X441533D03*
X438187D03*
X434840D03*
X431494D03*
X428147D03*
X424801D03*
X421455D03*
X418108D03*
X478344Y542824D03*
X474998D03*
X471651D03*
X468305D03*
X464958D03*
X461612D03*
X458266D03*
X454919D03*
X451573D03*
X448226D03*
X444880D03*
X441533D03*
X438187D03*
X434840D03*
X431494D03*
X428147D03*
X424801D03*
X421455D03*
X418108D03*
X478344Y560934D03*
X474998D03*
X471651D03*
X468305D03*
X464958D03*
X461612D03*
X458266D03*
X454919D03*
X451573D03*
X448226D03*
X444880D03*
X441533D03*
X438187D03*
X434840D03*
X431494D03*
X428147D03*
X424801D03*
X421455D03*
X418108D03*
X478344Y598734D03*
X474998D03*
X471651D03*
X468305D03*
X464958D03*
X461612D03*
X458266D03*
X454919D03*
X451573D03*
X448226D03*
X444880D03*
X441533D03*
X438187D03*
X434840D03*
X431494D03*
X428147D03*
X424801D03*
X421455D03*
X418108D03*
X531888Y4023D03*
X538581D03*
X485037Y22133D03*
X491730D03*
X498423D03*
X508462D03*
X515155D03*
X521848D03*
X528541D03*
X535234D03*
X481691Y4023D03*
X488384D03*
X495077D03*
X501770D03*
X511809D03*
X518502D03*
X525195D03*
X508462D03*
X505116D03*
X538581Y22133D03*
X501770D03*
X505116D03*
X528541Y4023D03*
X525195Y22133D03*
X535234Y4023D03*
X531888Y22133D03*
X515155Y4023D03*
X511809Y22133D03*
X491730Y4023D03*
X488384Y22133D03*
X521848Y4023D03*
X518502Y22133D03*
X498423Y4023D03*
X495077Y22133D03*
X485037Y4023D03*
X481691Y22133D03*
X531888Y41823D03*
X538581D03*
X485037Y59933D03*
X491730D03*
X498423D03*
X508462D03*
X515155D03*
X521848D03*
X528541D03*
X535234D03*
X481691Y41823D03*
X488384D03*
X495077D03*
X501770D03*
X511809D03*
X518502D03*
X525195D03*
X508462D03*
X505116D03*
X538581Y59933D03*
X501770D03*
X505116D03*
X528541Y41823D03*
X525195Y59933D03*
X535234Y41823D03*
X531888Y59933D03*
X515155Y41823D03*
X511809Y59933D03*
X491730Y41823D03*
X488384Y59933D03*
X521848Y41823D03*
X518502Y59933D03*
X498423Y41823D03*
X495077Y59933D03*
X485037Y41823D03*
X481691Y59933D03*
X531888Y79623D03*
X538581D03*
X485037Y97733D03*
X491730D03*
X498423D03*
X508462D03*
X515155D03*
X521848D03*
X528541D03*
X535234D03*
X481691Y79623D03*
X488384D03*
X495077D03*
X501770D03*
X511809D03*
X518502D03*
X525195D03*
X508462D03*
X505116D03*
X538581Y97733D03*
X501770D03*
X505116D03*
X528541Y79623D03*
X525195Y97733D03*
X535234Y79623D03*
X531888Y97733D03*
X515155Y79623D03*
X511809Y97733D03*
X491730Y79623D03*
X488384Y97733D03*
X521848Y79623D03*
X518502Y97733D03*
X498423Y79623D03*
X495077Y97733D03*
X485037Y79623D03*
X481691Y97733D03*
X538581Y505024D03*
X535234D03*
X531888D03*
X528541D03*
X525195D03*
X521848D03*
X518502D03*
X515155D03*
X511809D03*
X508462D03*
X505116D03*
X501770D03*
X498423D03*
X495077D03*
X491730D03*
X488384D03*
X485037D03*
X481691D03*
X538581Y523134D03*
X535234D03*
X531888D03*
X528541D03*
X525195D03*
X521848D03*
X518502D03*
X515155D03*
X511809D03*
X508462D03*
X505116D03*
X501770D03*
X498423D03*
X495077D03*
X491730D03*
X488384D03*
X485037D03*
X481691D03*
X538581Y580624D03*
X535234D03*
X531888D03*
X528541D03*
X525195D03*
X521848D03*
X518502D03*
X515155D03*
X511809D03*
X508462D03*
X505116D03*
X501770D03*
X498423D03*
X495077D03*
X491730D03*
X488384D03*
X485037D03*
X481691D03*
X538581Y542824D03*
X535234D03*
X531888D03*
X528541D03*
X525195D03*
X521848D03*
X518502D03*
X515155D03*
X511809D03*
X508462D03*
X505116D03*
X501770D03*
X498423D03*
X495077D03*
X491730D03*
X488384D03*
X485037D03*
X481691D03*
X538581Y560934D03*
X535234D03*
X531888D03*
X528541D03*
X525195D03*
X521848D03*
X518502D03*
X515155D03*
X511809D03*
X508462D03*
X505116D03*
X501770D03*
X498423D03*
X495077D03*
X491730D03*
X488384D03*
X485037D03*
X481691D03*
X538581Y598734D03*
X535234D03*
X531888D03*
X528541D03*
X525195D03*
X521848D03*
X518502D03*
X515155D03*
X511809D03*
X508462D03*
X505116D03*
X501770D03*
X498423D03*
X495077D03*
X491730D03*
X488384D03*
X485037D03*
X481691D03*
X548620Y4023D03*
X555313D03*
X562006D03*
X545273Y22133D03*
X551966D03*
X558659D03*
X565352D03*
X572045D03*
X568699Y4023D03*
X582084Y22133D03*
X588777D03*
X595470D03*
X575392Y4023D03*
X585431D03*
X592124D03*
X598817D03*
X582084D03*
X578738D03*
X545273D03*
X541927D03*
X575392Y22133D03*
X578738D03*
X541927D03*
X602163Y4023D03*
Y22133D03*
X598817D03*
X588777Y4023D03*
X585431Y22133D03*
X565352Y4023D03*
X562006Y22133D03*
X595470Y4023D03*
X592124Y22133D03*
X572045Y4023D03*
X568699Y22133D03*
X551966Y4023D03*
X548620Y22133D03*
X558659Y4023D03*
X555313Y22133D03*
X548620Y41823D03*
X555313D03*
X562006D03*
X545273Y59933D03*
X551966D03*
X558659D03*
X565352D03*
X572045D03*
X568699Y41823D03*
X582084Y59933D03*
X588777D03*
X595470D03*
X575392Y41823D03*
X585431D03*
X592124D03*
X598817D03*
X582084D03*
X578738D03*
X545273D03*
X541927D03*
X575392Y59933D03*
X578738D03*
X541927D03*
X602163Y41823D03*
Y59933D03*
X598817D03*
X588777Y41823D03*
X585431Y59933D03*
X565352Y41823D03*
X562006Y59933D03*
X595470Y41823D03*
X592124Y59933D03*
X572045Y41823D03*
X568699Y59933D03*
X551966Y41823D03*
X548620Y59933D03*
X558659Y41823D03*
X555313Y59933D03*
X548620Y79623D03*
X555313D03*
X562006D03*
X545273Y97733D03*
X551966D03*
X558659D03*
X565352D03*
X572045D03*
X568699Y79623D03*
X582084Y97733D03*
X588777D03*
X595470D03*
X575392Y79623D03*
X585431D03*
X592124D03*
X598817D03*
X582084D03*
X578738D03*
X545273D03*
X541927D03*
X575392Y97733D03*
X578738D03*
X541927D03*
X602163Y79623D03*
Y97733D03*
X598817D03*
X588777Y79623D03*
X585431Y97733D03*
X565352Y79623D03*
X562006Y97733D03*
X595470Y79623D03*
X592124Y97733D03*
X572045Y79623D03*
X568699Y97733D03*
X551966Y79623D03*
X548620Y97733D03*
X558659Y79623D03*
X555313Y97733D03*
X602163Y505024D03*
X598817D03*
X595470D03*
X592124D03*
X588777D03*
X585431D03*
X582084D03*
X578738D03*
X575392D03*
X572045D03*
X568699D03*
X565352D03*
X562006D03*
X558659D03*
X555313D03*
X551966D03*
X548620D03*
X545273D03*
X541927D03*
X602163Y523134D03*
X598817D03*
X595470D03*
X592124D03*
X588777D03*
X585431D03*
X582084D03*
X578738D03*
X575392D03*
X572045D03*
X568699D03*
X565352D03*
X562006D03*
X558659D03*
X555313D03*
X551966D03*
X548620D03*
X545273D03*
X541927D03*
X602163Y580624D03*
X598817D03*
X595470D03*
X592124D03*
X588777D03*
X585431D03*
X582084D03*
X578738D03*
X575392D03*
X572045D03*
X568699D03*
X565352D03*
X562006D03*
X558659D03*
X555313D03*
X551966D03*
X548620D03*
X545273D03*
X541927D03*
X602163Y542824D03*
X598817D03*
X595470D03*
X592124D03*
X588777D03*
X585431D03*
X582084D03*
X578738D03*
X575392D03*
X572045D03*
X568699D03*
X565352D03*
X562006D03*
X558659D03*
X555313D03*
X551966D03*
X548620D03*
X545273D03*
X541927D03*
X602163Y560934D03*
X598817D03*
X595470D03*
X592124D03*
X588777D03*
X585431D03*
X582084D03*
X578738D03*
X575392D03*
X572045D03*
X568699D03*
X565352D03*
X562006D03*
X558659D03*
X555313D03*
X551966D03*
X548620D03*
X545273D03*
X541927D03*
X602163Y598734D03*
X598817D03*
X595470D03*
X592124D03*
X588777D03*
X585431D03*
X582084D03*
X578738D03*
X575392D03*
X572045D03*
X568699D03*
X565352D03*
X562006D03*
X558659D03*
X555313D03*
X551966D03*
X548620D03*
X545273D03*
X541927D03*
X608856Y22133D03*
X612203D03*
X615549Y4023D03*
X608856D03*
X612203D03*
X605510D03*
Y22133D03*
X615549D03*
X608856Y59933D03*
X612203D03*
X615549Y41823D03*
X608856D03*
X612203D03*
X605510D03*
Y59933D03*
X615549D03*
X608856Y97733D03*
X612203D03*
X615549Y79623D03*
X608856D03*
X612203D03*
X605510D03*
Y97733D03*
X615549D03*
Y505024D03*
X612203D03*
X608856D03*
X605510D03*
X615549Y523134D03*
X612203D03*
X608856D03*
X605510D03*
X615549Y580624D03*
X612203D03*
X608856D03*
X605510D03*
X615549Y542824D03*
X612203D03*
X608856D03*
X605510D03*
X615549Y560934D03*
X612203D03*
X608856D03*
X605510D03*
X615549Y598734D03*
X612203D03*
X608856D03*
X605510D03*
X786616Y4023D03*
X783269D03*
X779923D03*
X776576D03*
X773230D03*
X769883D03*
X766537D03*
X786616Y22133D03*
X783269D03*
X779923D03*
X776576D03*
X773230D03*
X769883D03*
X766537D03*
X786616Y79623D03*
X783269D03*
X779923D03*
X776576D03*
X773230D03*
X769883D03*
X766537D03*
X786616Y97733D03*
X783269D03*
X779923D03*
X776576D03*
X773230D03*
X769883D03*
X766537D03*
X786616Y41823D03*
X783269D03*
X779923D03*
X776576D03*
X773230D03*
X769883D03*
X766537D03*
X786616Y59933D03*
X783269D03*
X779923D03*
X776576D03*
X773230D03*
X769883D03*
X766537D03*
X786616Y505024D03*
X783269D03*
X779923D03*
X776576D03*
X773230D03*
X769883D03*
X766537D03*
X786616Y523134D03*
X783269D03*
X779923D03*
X776576D03*
X773230D03*
X769883D03*
X766537D03*
X786616Y580624D03*
X783269D03*
X779923D03*
X776576D03*
X773230D03*
X769883D03*
X766537D03*
X786616Y542824D03*
X783269D03*
X779923D03*
X776576D03*
X773230D03*
X769883D03*
X766537D03*
X786616Y560934D03*
X783269D03*
X779923D03*
X776576D03*
X773230D03*
X769883D03*
X766537D03*
X786616Y598734D03*
X783269D03*
X779923D03*
X776576D03*
X773230D03*
X769883D03*
X766537D03*
X846852Y4023D03*
X843506D03*
X840159D03*
X836813D03*
X833466D03*
X830120D03*
X826773D03*
X823427D03*
X820080D03*
X816734D03*
X813387D03*
X810041D03*
X806694D03*
X803348D03*
X800002D03*
X796655D03*
X793309D03*
X789962D03*
X846852Y22133D03*
X843506D03*
X840159D03*
X836813D03*
X833466D03*
X830120D03*
X826773D03*
X823427D03*
X820080D03*
X816734D03*
X813387D03*
X810041D03*
X806694D03*
X803348D03*
X800002D03*
X796655D03*
X793309D03*
X789962D03*
X846852Y79623D03*
X843506D03*
X840159D03*
X836813D03*
X833466D03*
X830120D03*
X826773D03*
X823427D03*
X820080D03*
X816734D03*
X813387D03*
X810041D03*
X806694D03*
X803348D03*
X800002D03*
X796655D03*
X793309D03*
X789962D03*
X846852Y97733D03*
X843506D03*
X840159D03*
X836813D03*
X833466D03*
X830120D03*
X826773D03*
X823427D03*
X820080D03*
X816734D03*
X813387D03*
X810041D03*
X806694D03*
X803348D03*
X800002D03*
X796655D03*
X793309D03*
X789962D03*
X846852Y41823D03*
X843506D03*
X840159D03*
X836813D03*
X833466D03*
X830120D03*
X826773D03*
X823427D03*
X820080D03*
X816734D03*
X813387D03*
X810041D03*
X806694D03*
X803348D03*
X800002D03*
X796655D03*
X793309D03*
X789962D03*
X846852Y59933D03*
X843506D03*
X840159D03*
X836813D03*
X833466D03*
X830120D03*
X826773D03*
X823427D03*
X820080D03*
X816734D03*
X813387D03*
X810041D03*
X806694D03*
X803348D03*
X800002D03*
X796655D03*
X793309D03*
X789962D03*
X846852Y505024D03*
X843506D03*
X840159D03*
X836813D03*
X833466D03*
X830120D03*
X826773D03*
X823427D03*
X820080D03*
X816734D03*
X813387D03*
X810041D03*
X806694D03*
X803348D03*
X800002D03*
X796655D03*
X793309D03*
X789962D03*
X846852Y523134D03*
X843506D03*
X840159D03*
X836813D03*
X833466D03*
X830120D03*
X826773D03*
X823427D03*
X820080D03*
X816734D03*
X813387D03*
X810041D03*
X806694D03*
X803348D03*
X800002D03*
X796655D03*
X793309D03*
X789962D03*
X846852Y580624D03*
X843506D03*
X840159D03*
X836813D03*
X833466D03*
X830120D03*
X826773D03*
X823427D03*
X820080D03*
X816734D03*
X813387D03*
X810041D03*
X806694D03*
X803348D03*
X800002D03*
X796655D03*
X793309D03*
X789962D03*
X846852Y542824D03*
X843506D03*
X840159D03*
X836813D03*
X833466D03*
X830120D03*
X826773D03*
X823427D03*
X820080D03*
X816734D03*
X813387D03*
X810041D03*
X806694D03*
X803348D03*
X800002D03*
X796655D03*
X793309D03*
X789962D03*
X846852Y560934D03*
X843506D03*
X840159D03*
X836813D03*
X833466D03*
X830120D03*
X826773D03*
X823427D03*
X820080D03*
X816734D03*
X813387D03*
X810041D03*
X806694D03*
X803348D03*
X800002D03*
X796655D03*
X793309D03*
X789962D03*
X846852Y598734D03*
X843506D03*
X840159D03*
X836813D03*
X833466D03*
X830120D03*
X826773D03*
X823427D03*
X820080D03*
X816734D03*
X813387D03*
X810041D03*
X806694D03*
X803348D03*
X800002D03*
X796655D03*
X793309D03*
X789962D03*
X910435Y4023D03*
X907088D03*
X903742D03*
X900395D03*
X897049D03*
X893702D03*
X890356D03*
X887009D03*
X883663D03*
X880317D03*
X876970D03*
X873624D03*
X870277D03*
X866931D03*
X863584D03*
X860238D03*
X856891D03*
X853545D03*
X850198D03*
X910435Y22133D03*
X907088D03*
X903742D03*
X900395D03*
X897049D03*
X893702D03*
X890356D03*
X887009D03*
X883663D03*
X880317D03*
X876970D03*
X873624D03*
X870277D03*
X866931D03*
X863584D03*
X860238D03*
X856891D03*
X853545D03*
X850198D03*
X910435Y79623D03*
X907088D03*
X903742D03*
X900395D03*
X897049D03*
X893702D03*
X890356D03*
X887009D03*
X883663D03*
X880317D03*
X876970D03*
X873624D03*
X870277D03*
X866931D03*
X863584D03*
X860238D03*
X856891D03*
X853545D03*
X850198D03*
X910435Y97733D03*
X907088D03*
X903742D03*
X900395D03*
X897049D03*
X893702D03*
X890356D03*
X887009D03*
X883663D03*
X880317D03*
X876970D03*
X873624D03*
X870277D03*
X866931D03*
X863584D03*
X860238D03*
X856891D03*
X853545D03*
X850198D03*
X910435Y41823D03*
X907088D03*
X903742D03*
X900395D03*
X897049D03*
X893702D03*
X890356D03*
X887009D03*
X883663D03*
X880317D03*
X876970D03*
X873624D03*
X870277D03*
X866931D03*
X863584D03*
X860238D03*
X856891D03*
X853545D03*
X850198D03*
X910435Y59933D03*
X907088D03*
X903742D03*
X900395D03*
X897049D03*
X893702D03*
X890356D03*
X887009D03*
X883663D03*
X880317D03*
X876970D03*
X873624D03*
X870277D03*
X866931D03*
X863584D03*
X860238D03*
X856891D03*
X853545D03*
X850198D03*
X910435Y505024D03*
X907088D03*
X903742D03*
X900395D03*
X897049D03*
X893702D03*
X890356D03*
X887009D03*
X883663D03*
X880317D03*
X876970D03*
X873624D03*
X870277D03*
X866931D03*
X863584D03*
X860238D03*
X856891D03*
X853545D03*
X850198D03*
X910435Y523134D03*
X907088D03*
X903742D03*
X900395D03*
X897049D03*
X893702D03*
X890356D03*
X887009D03*
X883663D03*
X880317D03*
X876970D03*
X873624D03*
X870277D03*
X866931D03*
X863584D03*
X860238D03*
X856891D03*
X853545D03*
X850198D03*
X910435Y580624D03*
X907088D03*
X903742D03*
X900395D03*
X897049D03*
X893702D03*
X890356D03*
X887009D03*
X883663D03*
X880317D03*
X876970D03*
X873624D03*
X870277D03*
X866931D03*
X863584D03*
X860238D03*
X856891D03*
X853545D03*
X850198D03*
X910435Y542824D03*
X907088D03*
X903742D03*
X900395D03*
X897049D03*
X893702D03*
X890356D03*
X887009D03*
X883663D03*
X880317D03*
X876970D03*
X873624D03*
X870277D03*
X866931D03*
X863584D03*
X860238D03*
X856891D03*
X853545D03*
X850198D03*
X910435Y560934D03*
X907088D03*
X903742D03*
X900395D03*
X897049D03*
X893702D03*
X890356D03*
X887009D03*
X883663D03*
X880317D03*
X876970D03*
X873624D03*
X870277D03*
X866931D03*
X863584D03*
X860238D03*
X856891D03*
X853545D03*
X850198D03*
X910435Y598734D03*
X907088D03*
X903742D03*
X900395D03*
X897049D03*
X893702D03*
X890356D03*
X887009D03*
X883663D03*
X880317D03*
X876970D03*
X873624D03*
X870277D03*
X866931D03*
X863584D03*
X860238D03*
X856891D03*
X853545D03*
X850198D03*
X970671Y4023D03*
X967324D03*
X963978D03*
X960631D03*
X957285D03*
X953939D03*
X950592D03*
X947246D03*
X943899D03*
X940553D03*
X937206D03*
X933860D03*
X930513D03*
X927167D03*
X923820D03*
X920474D03*
X917128D03*
X913781D03*
X970671Y22133D03*
X967324D03*
X963978D03*
X960631D03*
X957285D03*
X953939D03*
X950592D03*
X947246D03*
X943899D03*
X940553D03*
X937206D03*
X933860D03*
X930513D03*
X927167D03*
X923820D03*
X920474D03*
X917128D03*
X913781D03*
X970671Y79623D03*
X967324D03*
X963978D03*
X960631D03*
X957285D03*
X953939D03*
X950592D03*
X947246D03*
X943899D03*
X940553D03*
X937206D03*
X933860D03*
X930513D03*
X927167D03*
X923820D03*
X920474D03*
X917128D03*
X913781D03*
X970671Y97733D03*
X967324D03*
X963978D03*
X960631D03*
X957285D03*
X953939D03*
X950592D03*
X947246D03*
X943899D03*
X940553D03*
X937206D03*
X933860D03*
X930513D03*
X927167D03*
X923820D03*
X920474D03*
X917128D03*
X913781D03*
X970671Y41823D03*
X967324D03*
X963978D03*
X960631D03*
X957285D03*
X953939D03*
X950592D03*
X947246D03*
X943899D03*
X940553D03*
X937206D03*
X933860D03*
X930513D03*
X927167D03*
X923820D03*
X920474D03*
X917128D03*
X913781D03*
X970671Y59933D03*
X967324D03*
X963978D03*
X960631D03*
X957285D03*
X953939D03*
X950592D03*
X947246D03*
X943899D03*
X940553D03*
X937206D03*
X933860D03*
X930513D03*
X927167D03*
X923820D03*
X920474D03*
X917128D03*
X913781D03*
X970671Y505024D03*
X967324D03*
X963978D03*
X960631D03*
X957285D03*
X953939D03*
X950592D03*
X947246D03*
X943899D03*
X940553D03*
X937206D03*
X933860D03*
X930513D03*
X927167D03*
X923820D03*
X920474D03*
X917128D03*
X913781D03*
X970671Y523134D03*
X967324D03*
X963978D03*
X960631D03*
X957285D03*
X953939D03*
X950592D03*
X947246D03*
X943899D03*
X940553D03*
X937206D03*
X933860D03*
X930513D03*
X927167D03*
X923820D03*
X920474D03*
X917128D03*
X913781D03*
X970671Y580624D03*
X967324D03*
X963978D03*
X960631D03*
X957285D03*
X953939D03*
X950592D03*
X947246D03*
X943899D03*
X940553D03*
X937206D03*
X933860D03*
X930513D03*
X927167D03*
X923820D03*
X920474D03*
X917128D03*
X913781D03*
X970671Y542824D03*
X967324D03*
X963978D03*
X960631D03*
X957285D03*
X953939D03*
X950592D03*
X947246D03*
X943899D03*
X940553D03*
X937206D03*
X933860D03*
X930513D03*
X927167D03*
X923820D03*
X920474D03*
X917128D03*
X913781D03*
X970671Y560934D03*
X967324D03*
X963978D03*
X960631D03*
X957285D03*
X953939D03*
X950592D03*
X947246D03*
X943899D03*
X940553D03*
X937206D03*
X933860D03*
X930513D03*
X927167D03*
X923820D03*
X920474D03*
X917128D03*
X913781D03*
X970671Y598734D03*
X967324D03*
X963978D03*
X960631D03*
X957285D03*
X953939D03*
X950592D03*
X947246D03*
X943899D03*
X940553D03*
X937206D03*
X933860D03*
X930513D03*
X927167D03*
X923820D03*
X920474D03*
X917128D03*
X913781D03*
X1020868Y4023D03*
X1017521D03*
X1014175D03*
X1010828D03*
X1007482D03*
X1004135D03*
X1000789D03*
X997443D03*
X994096D03*
X990750D03*
X987403D03*
X984057D03*
X980710D03*
X977364D03*
X974017D03*
X1020868Y22133D03*
X1017521D03*
X1014175D03*
X1010828D03*
X1007482D03*
X1004135D03*
X1000789D03*
X997443D03*
X994096D03*
X990750D03*
X987403D03*
X984057D03*
X980710D03*
X977364D03*
X974017D03*
X1020868Y79623D03*
X1017521D03*
X1014175D03*
X1010828D03*
X1007482D03*
X1004135D03*
X1000789D03*
X997443D03*
X994096D03*
X990750D03*
X987403D03*
X984057D03*
X980710D03*
X977364D03*
X974017D03*
X1020868Y97733D03*
X1017521D03*
X1014175D03*
X1010828D03*
X1007482D03*
X1004135D03*
X1000789D03*
X997443D03*
X994096D03*
X990750D03*
X987403D03*
X984057D03*
X980710D03*
X977364D03*
X974017D03*
X1020868Y41823D03*
X1017521D03*
X1014175D03*
X1010828D03*
X1007482D03*
X1004135D03*
X1000789D03*
X997443D03*
X994096D03*
X990750D03*
X987403D03*
X984057D03*
X980710D03*
X977364D03*
X974017D03*
X1020868Y59933D03*
X1017521D03*
X1014175D03*
X1010828D03*
X1007482D03*
X1004135D03*
X1000789D03*
X997443D03*
X994096D03*
X990750D03*
X987403D03*
X984057D03*
X980710D03*
X977364D03*
X974017D03*
X1020868Y505024D03*
X1017521D03*
X1014175D03*
X1010828D03*
X1007482D03*
X1004135D03*
X1000789D03*
X997443D03*
X994096D03*
X990750D03*
X987403D03*
X984057D03*
X980710D03*
X977364D03*
X974017D03*
X1020868Y523134D03*
X1017521D03*
X1014175D03*
X1010828D03*
X1007482D03*
X1004135D03*
X1000789D03*
X997443D03*
X994096D03*
X990750D03*
X987403D03*
X984057D03*
X980710D03*
X977364D03*
X974017D03*
X1020868Y580624D03*
X1017521D03*
X1014175D03*
X1010828D03*
X1007482D03*
X1004135D03*
X1000789D03*
X997443D03*
X994096D03*
X990750D03*
X987403D03*
X984057D03*
X980710D03*
X977364D03*
X974017D03*
X1020868Y542824D03*
X1017521D03*
X1014175D03*
X1010828D03*
X1007482D03*
X1004135D03*
X1000789D03*
X997443D03*
X994096D03*
X990750D03*
X987403D03*
X984057D03*
X980710D03*
X977364D03*
X974017D03*
X1020868Y560934D03*
X1017521D03*
X1014175D03*
X1010828D03*
X1007482D03*
X1004135D03*
X1000789D03*
X997443D03*
X994096D03*
X990750D03*
X987403D03*
X984057D03*
X980710D03*
X977364D03*
X974017D03*
X1020868Y598734D03*
X1017521D03*
X1014175D03*
X1010828D03*
X1007482D03*
X1004135D03*
X1000789D03*
X997443D03*
X994096D03*
X990750D03*
X987403D03*
X984057D03*
X980710D03*
X977364D03*
X974017D03*
X1094490Y4023D03*
X1091143D03*
X1087797D03*
X1084450D03*
X1081104D03*
X1077757D03*
X1074411D03*
X1071065D03*
X1067718D03*
X1064372D03*
X1061025D03*
X1057679D03*
X1054332D03*
X1050986D03*
X1047639D03*
X1044293D03*
X1094490Y22133D03*
X1091143D03*
X1087797D03*
X1084450D03*
X1081104D03*
X1077757D03*
X1074411D03*
X1071065D03*
X1067718D03*
X1064372D03*
X1061025D03*
X1057679D03*
X1054332D03*
X1050986D03*
X1047639D03*
X1044293D03*
X1094490Y79623D03*
X1091143D03*
X1087797D03*
X1084450D03*
X1081104D03*
X1077757D03*
X1074411D03*
X1071065D03*
X1067718D03*
X1064372D03*
X1061025D03*
X1057679D03*
X1054332D03*
X1050986D03*
X1047639D03*
X1044293D03*
X1094490Y97733D03*
X1091143D03*
X1087797D03*
X1084450D03*
X1081104D03*
X1077757D03*
X1074411D03*
X1071065D03*
X1067718D03*
X1064372D03*
X1061025D03*
X1057679D03*
X1054332D03*
X1050986D03*
X1047639D03*
X1044293D03*
X1094490Y41823D03*
X1091143D03*
X1087797D03*
X1084450D03*
X1081104D03*
X1077757D03*
X1074411D03*
X1071065D03*
X1067718D03*
X1064372D03*
X1061025D03*
X1057679D03*
X1054332D03*
X1050986D03*
X1047639D03*
X1044293D03*
X1094490Y59933D03*
X1091143D03*
X1087797D03*
X1084450D03*
X1081104D03*
X1077757D03*
X1074411D03*
X1071065D03*
X1067718D03*
X1064372D03*
X1061025D03*
X1057679D03*
X1054332D03*
X1050986D03*
X1047639D03*
X1044293D03*
X1094490Y505024D03*
X1091143D03*
X1087797D03*
X1084450D03*
X1081104D03*
X1077757D03*
X1074411D03*
X1071065D03*
X1067718D03*
X1064372D03*
X1061025D03*
X1057679D03*
X1054332D03*
X1050986D03*
X1047639D03*
X1044293D03*
X1094490Y523134D03*
X1091143D03*
X1087797D03*
X1084450D03*
X1081104D03*
X1077757D03*
X1074411D03*
X1071065D03*
X1067718D03*
X1064372D03*
X1061025D03*
X1057679D03*
X1054332D03*
X1050986D03*
X1047639D03*
X1044293D03*
X1094490Y580624D03*
X1091143D03*
X1087797D03*
X1084450D03*
X1081104D03*
X1077757D03*
X1074411D03*
X1071065D03*
X1067718D03*
X1064372D03*
X1061025D03*
X1057679D03*
X1054332D03*
X1050986D03*
X1047639D03*
X1044293D03*
X1094490Y542824D03*
X1091143D03*
X1087797D03*
X1084450D03*
X1081104D03*
X1077757D03*
X1074411D03*
X1071065D03*
X1067718D03*
X1064372D03*
X1061025D03*
X1057679D03*
X1054332D03*
X1050986D03*
X1047639D03*
X1044293D03*
X1094490Y560934D03*
X1091143D03*
X1087797D03*
X1084450D03*
X1081104D03*
X1077757D03*
X1074411D03*
X1071065D03*
X1067718D03*
X1064372D03*
X1061025D03*
X1057679D03*
X1054332D03*
X1050986D03*
X1047639D03*
X1044293D03*
X1094490Y598734D03*
X1091143D03*
X1087797D03*
X1084450D03*
X1081104D03*
X1077757D03*
X1074411D03*
X1071065D03*
X1067718D03*
X1064372D03*
X1061025D03*
X1057679D03*
X1054332D03*
X1050986D03*
X1047639D03*
X1044293D03*
X1154726Y4023D03*
X1151380D03*
X1148033D03*
X1144687D03*
X1141340D03*
X1137994D03*
X1134647D03*
X1131301D03*
X1127954D03*
X1124608D03*
X1121261D03*
X1117915D03*
X1114568D03*
X1111222D03*
X1107876D03*
X1104529D03*
X1101183D03*
X1097836D03*
X1154726Y22133D03*
X1151380D03*
X1148033D03*
X1144687D03*
X1141340D03*
X1137994D03*
X1134647D03*
X1131301D03*
X1127954D03*
X1124608D03*
X1121261D03*
X1117915D03*
X1114568D03*
X1111222D03*
X1107876D03*
X1104529D03*
X1101183D03*
X1097836D03*
X1154726Y79623D03*
X1151380D03*
X1148033D03*
X1144687D03*
X1141340D03*
X1137994D03*
X1134647D03*
X1131301D03*
X1127954D03*
X1124608D03*
X1121261D03*
X1117915D03*
X1114568D03*
X1111222D03*
X1107876D03*
X1104529D03*
X1101183D03*
X1097836D03*
X1154726Y97733D03*
X1151380D03*
X1148033D03*
X1144687D03*
X1141340D03*
X1137994D03*
X1134647D03*
X1131301D03*
X1127954D03*
X1124608D03*
X1121261D03*
X1117915D03*
X1114568D03*
X1111222D03*
X1107876D03*
X1104529D03*
X1101183D03*
X1097836D03*
X1154726Y41823D03*
X1151380D03*
X1148033D03*
X1144687D03*
X1141340D03*
X1137994D03*
X1134647D03*
X1131301D03*
X1127954D03*
X1124608D03*
X1121261D03*
X1117915D03*
X1114568D03*
X1111222D03*
X1107876D03*
X1104529D03*
X1101183D03*
X1097836D03*
X1154726Y59933D03*
X1151380D03*
X1148033D03*
X1144687D03*
X1141340D03*
X1137994D03*
X1134647D03*
X1131301D03*
X1127954D03*
X1124608D03*
X1121261D03*
X1117915D03*
X1114568D03*
X1111222D03*
X1107876D03*
X1104529D03*
X1101183D03*
X1097836D03*
X1154726Y505024D03*
X1151380D03*
X1148033D03*
X1144687D03*
X1141340D03*
X1137994D03*
X1134647D03*
X1131301D03*
X1127954D03*
X1124608D03*
X1121261D03*
X1117915D03*
X1114568D03*
X1111222D03*
X1107876D03*
X1104529D03*
X1101183D03*
X1097836D03*
X1154726Y523134D03*
X1151380D03*
X1148033D03*
X1144687D03*
X1141340D03*
X1137994D03*
X1134647D03*
X1131301D03*
X1127954D03*
X1124608D03*
X1121261D03*
X1117915D03*
X1114568D03*
X1111222D03*
X1107876D03*
X1104529D03*
X1101183D03*
X1097836D03*
X1154726Y580624D03*
X1151380D03*
X1148033D03*
X1144687D03*
X1141340D03*
X1137994D03*
X1134647D03*
X1131301D03*
X1127954D03*
X1124608D03*
X1121261D03*
X1117915D03*
X1114568D03*
X1111222D03*
X1107876D03*
X1104529D03*
X1101183D03*
X1097836D03*
X1154726Y542824D03*
X1151380D03*
X1148033D03*
X1144687D03*
X1141340D03*
X1137994D03*
X1134647D03*
X1131301D03*
X1127954D03*
X1124608D03*
X1121261D03*
X1117915D03*
X1114568D03*
X1111222D03*
X1107876D03*
X1104529D03*
X1101183D03*
X1097836D03*
X1154726Y560934D03*
X1151380D03*
X1148033D03*
X1144687D03*
X1141340D03*
X1137994D03*
X1134647D03*
X1131301D03*
X1127954D03*
X1124608D03*
X1121261D03*
X1117915D03*
X1114568D03*
X1111222D03*
X1107876D03*
X1104529D03*
X1101183D03*
X1097836D03*
X1154726Y598734D03*
X1151380D03*
X1148033D03*
X1144687D03*
X1141340D03*
X1137994D03*
X1134647D03*
X1131301D03*
X1127954D03*
X1124608D03*
X1121261D03*
X1117915D03*
X1114568D03*
X1111222D03*
X1107876D03*
X1104529D03*
X1101183D03*
X1097836D03*
X1218309Y4023D03*
X1214962D03*
X1211616D03*
X1208269D03*
X1204923D03*
X1201576D03*
X1198230D03*
X1194883D03*
X1191537D03*
X1188191D03*
X1184844D03*
X1181498D03*
X1178151D03*
X1174805D03*
X1171458D03*
X1168112D03*
X1164765D03*
X1161419D03*
X1158072D03*
X1218309Y22133D03*
X1214962D03*
X1211616D03*
X1208269D03*
X1204923D03*
X1201576D03*
X1198230D03*
X1194883D03*
X1191537D03*
X1188191D03*
X1184844D03*
X1181498D03*
X1178151D03*
X1174805D03*
X1171458D03*
X1168112D03*
X1164765D03*
X1161419D03*
X1158072D03*
X1218309Y79623D03*
X1214962D03*
X1211616D03*
X1208269D03*
X1204923D03*
X1201576D03*
X1198230D03*
X1194883D03*
X1191537D03*
X1188191D03*
X1184844D03*
X1181498D03*
X1178151D03*
X1174805D03*
X1171458D03*
X1168112D03*
X1164765D03*
X1161419D03*
X1158072D03*
X1218309Y97733D03*
X1214962D03*
X1211616D03*
X1208269D03*
X1204923D03*
X1201576D03*
X1198230D03*
X1194883D03*
X1191537D03*
X1188191D03*
X1184844D03*
X1181498D03*
X1178151D03*
X1174805D03*
X1171458D03*
X1168112D03*
X1164765D03*
X1161419D03*
X1158072D03*
X1218309Y41823D03*
X1214962D03*
X1211616D03*
X1208269D03*
X1204923D03*
X1201576D03*
X1198230D03*
X1194883D03*
X1191537D03*
X1188191D03*
X1184844D03*
X1181498D03*
X1178151D03*
X1174805D03*
X1171458D03*
X1168112D03*
X1164765D03*
X1161419D03*
X1158072D03*
X1218309Y59933D03*
X1214962D03*
X1211616D03*
X1208269D03*
X1204923D03*
X1201576D03*
X1198230D03*
X1194883D03*
X1191537D03*
X1188191D03*
X1184844D03*
X1181498D03*
X1178151D03*
X1174805D03*
X1171458D03*
X1168112D03*
X1164765D03*
X1161419D03*
X1158072D03*
X1218309Y505024D03*
X1214962D03*
X1211616D03*
X1208269D03*
X1204923D03*
X1201576D03*
X1198230D03*
X1194883D03*
X1191537D03*
X1188191D03*
X1184844D03*
X1181498D03*
X1178151D03*
X1174805D03*
X1171458D03*
X1168112D03*
X1164765D03*
X1161419D03*
X1158072D03*
X1218309Y523134D03*
X1214962D03*
X1211616D03*
X1208269D03*
X1204923D03*
X1201576D03*
X1198230D03*
X1194883D03*
X1191537D03*
X1188191D03*
X1184844D03*
X1181498D03*
X1178151D03*
X1174805D03*
X1171458D03*
X1168112D03*
X1164765D03*
X1161419D03*
X1158072D03*
X1218309Y580624D03*
X1214962D03*
X1211616D03*
X1208269D03*
X1204923D03*
X1201576D03*
X1198230D03*
X1194883D03*
X1191537D03*
X1188191D03*
X1184844D03*
X1181498D03*
X1178151D03*
X1174805D03*
X1171458D03*
X1168112D03*
X1164765D03*
X1161419D03*
X1158072D03*
X1218309Y542824D03*
X1214962D03*
X1211616D03*
X1208269D03*
X1204923D03*
X1201576D03*
X1198230D03*
X1194883D03*
X1191537D03*
X1188191D03*
X1184844D03*
X1181498D03*
X1178151D03*
X1174805D03*
X1171458D03*
X1168112D03*
X1164765D03*
X1161419D03*
X1158072D03*
X1218309Y560934D03*
X1214962D03*
X1211616D03*
X1208269D03*
X1204923D03*
X1201576D03*
X1198230D03*
X1194883D03*
X1191537D03*
X1188191D03*
X1184844D03*
X1181498D03*
X1178151D03*
X1174805D03*
X1171458D03*
X1168112D03*
X1164765D03*
X1161419D03*
X1158072D03*
X1218309Y598734D03*
X1214962D03*
X1211616D03*
X1208269D03*
X1204923D03*
X1201576D03*
X1198230D03*
X1194883D03*
X1191537D03*
X1188191D03*
X1184844D03*
X1181498D03*
X1178151D03*
X1174805D03*
X1171458D03*
X1168112D03*
X1164765D03*
X1161419D03*
X1158072D03*
X1265159Y4023D03*
X1261813D03*
X1258466D03*
X1255120D03*
X1251773D03*
X1248427D03*
X1245080D03*
X1241734D03*
X1238387D03*
X1235041D03*
X1231694D03*
X1228348D03*
X1225002D03*
X1221655D03*
X1265159Y22133D03*
X1261813D03*
X1258466D03*
X1255120D03*
X1251773D03*
X1248427D03*
X1245080D03*
X1241734D03*
X1238387D03*
X1235041D03*
X1231694D03*
X1228348D03*
X1225002D03*
X1221655D03*
X1265159Y79623D03*
X1261813D03*
X1258466D03*
X1255120D03*
X1251773D03*
X1248427D03*
X1245080D03*
X1241734D03*
X1238387D03*
X1235041D03*
X1231694D03*
X1228348D03*
X1225002D03*
X1221655D03*
X1265159Y97733D03*
X1261813D03*
X1258466D03*
X1255120D03*
X1251773D03*
X1248427D03*
X1245080D03*
X1241734D03*
X1238387D03*
X1235041D03*
X1231694D03*
X1228348D03*
X1225002D03*
X1221655D03*
X1265159Y41823D03*
X1261813D03*
X1258466D03*
X1255120D03*
X1251773D03*
X1248427D03*
X1245080D03*
X1241734D03*
X1238387D03*
X1235041D03*
X1231694D03*
X1228348D03*
X1225002D03*
X1221655D03*
X1265159Y59933D03*
X1261813D03*
X1258466D03*
X1255120D03*
X1251773D03*
X1248427D03*
X1245080D03*
X1241734D03*
X1238387D03*
X1235041D03*
X1231694D03*
X1228348D03*
X1225002D03*
X1221655D03*
X1265159Y505024D03*
X1261813D03*
X1258466D03*
X1255120D03*
X1251773D03*
X1248427D03*
X1245080D03*
X1241734D03*
X1238387D03*
X1235041D03*
X1231694D03*
X1228348D03*
X1225002D03*
X1221655D03*
X1265159Y523134D03*
X1261813D03*
X1258466D03*
X1255120D03*
X1251773D03*
X1248427D03*
X1245080D03*
X1241734D03*
X1238387D03*
X1235041D03*
X1231694D03*
X1228348D03*
X1225002D03*
X1221655D03*
X1265159Y580624D03*
X1261813D03*
X1258466D03*
X1255120D03*
X1251773D03*
X1248427D03*
X1245080D03*
X1241734D03*
X1238387D03*
X1235041D03*
X1231694D03*
X1228348D03*
X1225002D03*
X1221655D03*
X1265159Y542824D03*
X1261813D03*
X1258466D03*
X1255120D03*
X1251773D03*
X1248427D03*
X1245080D03*
X1241734D03*
X1238387D03*
X1235041D03*
X1231694D03*
X1228348D03*
X1225002D03*
X1221655D03*
X1265159Y560934D03*
X1261813D03*
X1258466D03*
X1255120D03*
X1251773D03*
X1248427D03*
X1245080D03*
X1241734D03*
X1238387D03*
X1235041D03*
X1231694D03*
X1228348D03*
X1225002D03*
X1221655D03*
X1265159Y598734D03*
X1261813D03*
X1258466D03*
X1255120D03*
X1251773D03*
X1248427D03*
X1245080D03*
X1241734D03*
X1238387D03*
X1235041D03*
X1231694D03*
X1228348D03*
X1225002D03*
X1221655D03*
G54D16*
X15050Y30424D03*
X22050D03*
X22437Y66673D03*
X15437D03*
X22328Y73174D03*
X15328D03*
X22328Y79674D03*
X15328D03*
X15050Y37654D03*
X22050D03*
X15060Y44854D03*
X22060D03*
X4300Y242800D03*
X11300D03*
X-11190Y454200D03*
X-4190D03*
X12300Y584000D03*
X5300D03*
X12300Y577500D03*
X5300D03*
X12300Y555500D03*
X5300D03*
X12300Y549000D03*
X5300D03*
X12300Y542500D03*
X5300D03*
X12300Y590500D03*
X5300D03*
X103600Y31978D03*
Y-8400D03*
Y69778D03*
X61000Y216102D03*
X54000D03*
X110600Y31978D03*
Y-8400D03*
Y69778D03*
X136263Y261516D03*
X129263D03*
X136263Y268116D03*
X129263D03*
X136263Y255016D03*
X129263D03*
X136263Y229516D03*
X129263D03*
X136263Y236116D03*
X129263D03*
X136263Y223016D03*
X129263D03*
X136263Y287016D03*
X129263D03*
X136263Y293516D03*
X129263D03*
X136263Y300116D03*
X129263D03*
X136263Y332116D03*
X129263D03*
X136263Y325516D03*
X129263D03*
X136263Y319016D03*
X129263D03*
X136263Y364116D03*
X129263D03*
X136263Y357516D03*
X129263D03*
X136263Y351016D03*
X129263D03*
X136263Y396116D03*
X129263D03*
X136263Y383016D03*
X129263D03*
X136263Y389516D03*
X129263D03*
X378292Y13078D03*
X371292D03*
X379692Y31978D03*
X372692D03*
X408892Y-15000D03*
X401892D03*
X415892D03*
X372592Y-5810D03*
X379592D03*
X378892Y69100D03*
X371892D03*
X378312Y51178D03*
X371312D03*
X375492Y106500D03*
X382492D03*
X384448Y272041D03*
X391448D03*
X389956Y329710D03*
X382956D03*
X378120Y551360D03*
X371120D03*
X378262Y532978D03*
X371262D03*
X377340Y589650D03*
X370340D03*
X378232Y570818D03*
X371232D03*
X413324Y617756D03*
X399824D03*
X406824D03*
X379760Y618220D03*
X372760D03*
X360706Y618127D03*
X367706D03*
X436392Y-15000D03*
X429392D03*
X422892D03*
X446392Y107500D03*
X439392D03*
X440148Y274841D03*
X447148D03*
X448250Y496390D03*
X441250D03*
X427324Y617756D03*
X434324D03*
X420324D03*
X664500Y60000D03*
X657500D03*
X664500Y52000D03*
X657500D03*
X725230Y-10380D03*
X718230D03*
X721130Y42955D03*
X696000Y203000D03*
X703000D03*
X696000Y216500D03*
X703000D03*
X696000Y209500D03*
X703000D03*
X688700Y313000D03*
X695700D03*
X721900Y529700D03*
X753208Y31978D03*
X760208D03*
X753208Y-8400D03*
X760208D03*
X753208Y69778D03*
X760208D03*
X728130Y42955D03*
X785932Y261133D03*
X778932D03*
X785932Y254633D03*
X778932D03*
X785932Y236533D03*
X778932D03*
X785932Y230033D03*
X778932D03*
X786000Y223300D03*
X779000D03*
X785932Y267633D03*
X778932D03*
X785932Y299833D03*
X778932D03*
X785932Y286833D03*
X778932D03*
X785932Y293333D03*
X778932D03*
X785932Y319653D03*
X778932D03*
X785932Y326153D03*
X778932D03*
X786332Y332653D03*
X779332D03*
X786000Y383000D03*
X779000D03*
X785932Y357633D03*
X778932D03*
X785932Y364133D03*
X778932D03*
X785932Y351133D03*
X778932D03*
X786000Y389500D03*
X779000D03*
X786000Y396000D03*
X779000D03*
X728900Y529700D03*
X1029300Y31978D03*
X1022300D03*
X1029400Y13078D03*
X1022400D03*
X1023621Y-15762D03*
X1030621D03*
X1028600Y51400D03*
X1021600D03*
X1029300Y69100D03*
X1022300D03*
X1031200Y104500D03*
X1034056Y272041D03*
X1032564Y329710D03*
X1028800Y532978D03*
X1021800D03*
X1028900Y551500D03*
X1021900D03*
X1028300Y570778D03*
X1021300D03*
X1027070Y589650D03*
X1020070D03*
X1030700Y618200D03*
X1023700D03*
X1011234Y618177D03*
X1018234D03*
X1058500Y-15000D03*
X1051500D03*
X1072500D03*
X1065500D03*
X1086000D03*
X1079000D03*
X1096000Y105781D03*
X1089000D03*
X1038200Y104500D03*
X1089756Y274841D03*
X1096756D03*
X1041056Y272041D03*
X1039564Y329710D03*
X1041800Y496200D03*
X1048800D03*
X1095532Y617956D03*
X1088532D03*
X1068032D03*
X1061032D03*
X1081532D03*
X1074532D03*
X1320700Y111450D03*
X1313700D03*
X1320700Y119450D03*
X1313700D03*
X1360989Y-4107D03*
X1367989D03*
X1360989Y-10607D03*
X1367989D03*
X1360989Y-17207D03*
X1367989D03*
X1361400Y15200D03*
X1368400D03*
X1361400Y21700D03*
X1368400D03*
X1361400Y28200D03*
X1368400D03*
X1390531Y90354D03*
X1383531D03*
X1390531Y104354D03*
X1383531D03*
X1363700Y373500D03*
X1370700D03*
X1363800Y380200D03*
X1370800D03*
X1363700Y386700D03*
X1370700D03*
X1365500Y576156D03*
X1372500D03*
X1365500Y569156D03*
X1372500D03*
X1365500Y562656D03*
X1372500D03*
X1365400Y605800D03*
X1372400D03*
X1365100Y598576D03*
X1372100D03*
X1365100Y592076D03*
X1372100D03*
X1585270Y558204D03*
Y565204D03*
X1635876Y190731D03*
X1628876D03*
X1592270Y558204D03*
Y565204D03*
X1770600Y46800D03*
X1766600Y37800D03*
X1774600D03*
X1837000Y48500D03*
X1830000D03*
X1817772Y47218D03*
X1824772D03*
X1829800Y492500D03*
X1836800D03*
X1829800Y486000D03*
X1836800D03*
X1928000Y440730D03*
X1921000D03*
X1908000D03*
X1915000D03*
G54D163*
X1941937Y139548D03*
Y145452D03*
Y143484D03*
X1929937Y145452D03*
Y143484D03*
Y141516D03*
Y139548D03*
X1941937Y141516D03*
X1956376Y145503D03*
Y143535D03*
Y141567D03*
Y139599D03*
X1968376D03*
Y145503D03*
Y143535D03*
Y141567D03*
G54D61*
X580659Y334764D03*
G54D109*
X1458271Y446520D03*
G54D127*
X1629849Y156438D03*
X1685800Y165650D03*
X1785703Y69879D03*
X1839250Y98250D03*
G54D137*
X1690860Y124143D03*
G54D146*
X1750315Y560887D03*
Y566793D03*
X1803950Y538954D03*
Y533048D03*
G54D53*
X317942Y32100D03*
X312442D03*
X330142D03*
X324642D03*
X343142D03*
X337642D03*
X348000D03*
X353500D03*
X317942Y69900D03*
X312442D03*
X330142D03*
X324642D03*
X343142D03*
X337642D03*
X348000D03*
X353500D03*
X307492Y109500D03*
X312992D03*
X323292Y107100D03*
X317792D03*
X307692Y495600D03*
X313192D03*
X323670Y494675D03*
X318170D03*
X317942Y533100D03*
X312442D03*
X330142D03*
X324642D03*
X343142D03*
X337642D03*
X348000D03*
X353500D03*
X317942Y570900D03*
X312442D03*
X330142D03*
X324642D03*
X343142D03*
X337642D03*
X348000D03*
X353500D03*
X362392Y31800D03*
X367892D03*
X390900Y-15300D03*
X396400D03*
X399200Y32100D03*
X404700D03*
X411650D03*
X417150D03*
X361592Y69400D03*
X367092D03*
X399200Y69900D03*
X404700D03*
X411650D03*
X417150D03*
X383580Y497770D03*
X378080D03*
X360962Y532800D03*
X366462D03*
X401950Y533100D03*
X396450D03*
X360982Y570460D03*
X366482D03*
X411650Y533100D03*
X417150D03*
X399200Y570900D03*
X404700D03*
X411650D03*
X417150D03*
X424650Y32100D03*
X430150D03*
X437008D03*
X442508D03*
X424650Y69900D03*
X430150D03*
X437008D03*
X442508D03*
X445550Y113710D03*
X440050D03*
X452120Y490771D03*
X446620D03*
X424650Y533100D03*
X430150D03*
X438508D03*
X444008D03*
X424650Y570900D03*
X430150D03*
X437008D03*
X442508D03*
X967550Y32100D03*
X962050D03*
X967550Y69900D03*
X962050D03*
X972900Y107100D03*
X967400D03*
X957100Y109500D03*
X962600D03*
X957300Y494315D03*
X962800D03*
X967778D03*
X967550Y533100D03*
X962050D03*
X967550Y570900D03*
X962050D03*
X1012000Y31800D03*
X1017500D03*
X979750Y32100D03*
X974250D03*
X992750D03*
X987250D03*
X997608D03*
X1003108D03*
X1012000Y69400D03*
X1017500D03*
X979750Y69900D03*
X974250D03*
X992750D03*
X987250D03*
X997608D03*
X1003108D03*
X1020800Y104233D03*
X1026300D03*
X1017800Y496600D03*
X1023300D03*
X973278Y494315D03*
X1011500Y532800D03*
X1017000D03*
X1011050Y570400D03*
X1016550D03*
X979750Y533100D03*
X974250D03*
X992750D03*
X987250D03*
X997608D03*
X1003108D03*
X979750Y570900D03*
X974250D03*
X992750D03*
X987250D03*
X997608D03*
X1003108D03*
X1048808Y32100D03*
X1054308D03*
X1061258D03*
X1066758D03*
X1074258D03*
X1079758D03*
X1086616D03*
X1092116D03*
X1048808Y69900D03*
X1054308D03*
X1061258D03*
X1066758D03*
X1074258D03*
X1079758D03*
X1086616D03*
X1092116D03*
X1094900Y111400D03*
X1089400D03*
X1095788Y494860D03*
X1090288D03*
X1051558Y533100D03*
X1046058D03*
X1061258D03*
X1066758D03*
X1074258D03*
X1079758D03*
X1048808Y570900D03*
X1054308D03*
X1061258D03*
X1066758D03*
X1074258D03*
X1079758D03*
X1086616D03*
X1092116D03*
X1088116Y533100D03*
X1093616D03*
X1319119Y155667D03*
X1313619D03*
X1319119Y150629D03*
X1313619D03*
G54D155*
X1816654Y594001D03*
Y590064D03*
Y592032D03*
Y595970D03*
Y597938D03*
G54D173*
X1899972Y615413D03*
Y609913D03*
G54D164*
X1954041Y156109D03*
X1948921D03*
X1951481D03*
X1948921Y163364D03*
X1954041D03*
X1968871Y156309D03*
X1963751D03*
X1966311D03*
X1963751Y163564D03*
X1968871D03*
G54D35*
X83500Y229800D03*
Y234800D03*
Y239800D03*
Y224800D03*
G54D44*
X56872Y310550D03*
Y318050D03*
X48372Y314300D03*
X690704Y274026D03*
X682204Y277776D03*
Y270276D03*
X1497600Y164750D03*
Y172250D03*
X1489100Y168500D03*
X1518798Y166578D03*
Y174078D03*
X1510298Y170328D03*
X1628500Y31900D03*
Y24400D03*
X1637000Y28150D03*
X1648400Y67721D03*
Y60221D03*
X1648900Y53121D03*
Y45621D03*
X1652250Y275750D03*
X1643750Y279500D03*
X1652250Y283250D03*
X1646250Y311000D03*
X1656900Y63971D03*
X1657400Y49371D03*
X1654750Y307250D03*
Y314750D03*
X1743650Y74700D03*
X1735150Y78450D03*
X1743650Y82200D03*
X1774900Y599750D03*
X1766400Y603500D03*
Y596000D03*
X1893850Y575087D03*
Y582587D03*
X1885350Y578837D03*
X1904250Y556750D03*
X1912750Y553000D03*
X1904250Y549250D03*
G54D119*
X1554960Y145900D03*
Y153300D03*
X1557520Y145900D03*
Y153300D03*
X1552400Y145900D03*
Y153300D03*
X1847000Y516600D03*
Y525600D03*
X1853900Y516600D03*
Y525600D03*
G54D26*
X37000Y515600D03*
X48000D03*
X1728050Y255900D03*
X1739050D03*
G54D17*
X11980Y21330D03*
X15480D03*
X5440Y21090D03*
X8940D03*
X17276Y59655D03*
X13776D03*
X20260Y49500D03*
X16760D03*
X8500Y62800D03*
X5000D03*
X34900Y164100D03*
X38400D03*
X4800Y197300D03*
X8300D03*
X6500Y236000D03*
X10000D03*
X-8700Y449350D03*
X-5200D03*
X-13400Y502800D03*
X-9900D03*
X-13400Y506300D03*
X-9900D03*
X37568Y480095D03*
X34068D03*
X6500Y570300D03*
X3000D03*
X7000Y534500D03*
X3500D03*
X-1750Y574100D03*
X-5250D03*
X58308Y-14773D03*
X54808D03*
X58308Y-17864D03*
X54808D03*
X58316Y-11754D03*
X54816D03*
X93714Y124724D03*
X97214D03*
X94000Y118500D03*
X97500D03*
X67000Y183000D03*
X70500D03*
X67000Y186500D03*
X70500D03*
X51500Y163000D03*
X55000D03*
X66000Y166500D03*
X69500D03*
X51500Y159500D03*
X55000D03*
X93500Y223800D03*
X97000D03*
X105800Y338200D03*
X102300D03*
X76600Y331900D03*
X73100D03*
X92000Y338200D03*
X95500D03*
X92000Y327500D03*
X95500D03*
X76600Y307300D03*
X80100D03*
X87500Y313000D03*
X91000D03*
X67500Y319500D03*
X64000D03*
X73000Y324500D03*
X76500D03*
X73000Y328000D03*
X76500D03*
X65620Y296680D03*
X62120D03*
X65520Y300680D03*
X62020D03*
X92370Y293020D03*
X88870D03*
X65000Y351500D03*
X68500D03*
X61100Y343150D03*
X64600D03*
X58000Y351000D03*
X54500D03*
X55130Y385820D03*
X51630D03*
X55130Y395520D03*
X51630D03*
X73730Y396080D03*
X70230D03*
X73730Y392580D03*
X70230D03*
X55130Y392020D03*
X51630D03*
X73730Y403380D03*
X70230D03*
X55110Y382340D03*
X51610D03*
X52330Y403420D03*
X48830D03*
X52330Y399920D03*
X48830D03*
X73730Y414180D03*
X70230D03*
X73730Y417680D03*
X70230D03*
X57990Y423170D03*
X54490D03*
X57990Y419670D03*
X54490D03*
X69730Y424980D03*
X66230D03*
X69730Y428480D03*
X66230D03*
X73730Y406880D03*
X70230D03*
X75830Y531361D03*
X79330D03*
X75846Y528307D03*
X79346D03*
X123392Y31978D03*
X119892D03*
X123392Y-6000D03*
X119892D03*
X123392Y69778D03*
X119892D03*
X130800Y214600D03*
X127300D03*
X130700Y278700D03*
X127200D03*
X130500Y246600D03*
X127000D03*
X130600Y310800D03*
X127100D03*
X130600Y342600D03*
X127100D03*
X130500Y374600D03*
X127000D03*
X151254Y417659D03*
X154754D03*
X151361Y420954D03*
X154861D03*
X151341Y424439D03*
X154841D03*
X164897Y410444D03*
X161397D03*
X164667Y407412D03*
X161167D03*
X123792Y532800D03*
X120292D03*
X123392Y570778D03*
X119892D03*
X123392Y608800D03*
X119892D03*
X251700Y366800D03*
X248200D03*
X252700Y362800D03*
X249200D03*
X252700Y358800D03*
X249200D03*
X252700Y354300D03*
X249200D03*
X252700Y349800D03*
X249200D03*
X313000Y253000D03*
X316500D03*
X313000Y256500D03*
X316500D03*
X312063Y341509D03*
X315563D03*
X312063Y345009D03*
X315563D03*
X343802Y496030D03*
X340302D03*
X444378Y117880D03*
X440878D03*
X452500Y278500D03*
X456000D03*
X438934Y270091D03*
X442434D03*
X461500Y301000D03*
X458000D03*
X461500Y295000D03*
X458000D03*
X457900Y283000D03*
X461400D03*
X458000Y307000D03*
X461500D03*
X458000Y304000D03*
X461500D03*
X458000Y310000D03*
X461500D03*
Y298000D03*
X458000D03*
X457900Y286000D03*
X461400D03*
X457900Y289000D03*
X461400D03*
X507472Y255647D03*
X510972D03*
X512430Y258547D03*
X515930D03*
X649600Y-9000D03*
X653100D03*
X659755Y-8699D03*
X656255D03*
X658300Y-4800D03*
X654800D03*
X656405Y89566D03*
X659905D03*
X656406Y92766D03*
X659906D03*
X653000Y264800D03*
X649500D03*
X653000Y261300D03*
X649500D03*
X646000Y272000D03*
X649500D03*
X646000Y268500D03*
X649500D03*
X644400Y302000D03*
X640900D03*
X644400Y316300D03*
X640900D03*
X644000Y327000D03*
X640500D03*
X644890Y337000D03*
X641390D03*
X644890Y332000D03*
X641390D03*
X644000Y322000D03*
X640500D03*
X644400Y312000D03*
X640900D03*
X644400Y307000D03*
X640900D03*
X653000Y320500D03*
X649500D03*
X653000Y316500D03*
X649500D03*
X653000Y333500D03*
X649500D03*
X612307Y470019D03*
X615807D03*
X660500Y494500D03*
X660320Y585600D03*
X663820D03*
X683950Y14500D03*
X687450D03*
X684726Y18015D03*
X688226D03*
X703919Y79550D03*
X700419D03*
X703919Y82850D03*
X700419D03*
X664888Y89189D03*
X668388D03*
X664888Y92766D03*
X668388D03*
X683000Y256000D03*
X686500D03*
X702000Y223500D03*
X705500D03*
X702036Y269061D03*
X705536D03*
X702011Y272561D03*
X705511D03*
X690000Y300500D03*
X693500D03*
X690251Y330500D03*
X693751D03*
X690251Y335500D03*
X693751D03*
X690420Y325500D03*
X693920D03*
X709100Y303600D03*
X712600D03*
Y300100D03*
X709100D03*
X690420Y320500D03*
X693920D03*
X690000Y305500D03*
X693500D03*
X686784Y291412D03*
X690284D03*
X681000Y317500D03*
X684500D03*
X681000Y321500D03*
X684500D03*
X681000Y333000D03*
X684500D03*
X670500Y494500D03*
X667000D03*
X664000D03*
X677400Y581900D03*
X673900D03*
X683600Y578500D03*
X687100D03*
X773000Y31978D03*
X769500D03*
X773000Y-6000D03*
X769500D03*
X773000Y69778D03*
X769500D03*
X780032Y214689D03*
X776532D03*
X780032Y246689D03*
X776532D03*
X780032Y278689D03*
X776532D03*
X772300Y252000D03*
X768800D03*
X772100Y220000D03*
X768600D03*
X780032Y310689D03*
X776532D03*
X771900Y284100D03*
X768400D03*
X771900Y315900D03*
X768400D03*
X779982Y374689D03*
X776482D03*
X780032Y342689D03*
X776532D03*
X772100Y380200D03*
X768600D03*
X772400Y348200D03*
X768900D03*
X726500Y574500D03*
X730000D03*
X773000Y570778D03*
X769500D03*
X773400Y532800D03*
X769900D03*
X773000Y608800D03*
X769500D03*
X806500Y415500D03*
X810000D03*
X806500Y418500D03*
X810000D03*
X806500Y412500D03*
X810000D03*
X898100Y341000D03*
X901600D03*
X899500Y367500D03*
X896000D03*
X899500Y364500D03*
X896000D03*
X899500Y361500D03*
X896000D03*
X899500Y355500D03*
X896000D03*
X899500Y358500D03*
X896000D03*
X898100Y344800D03*
X901600D03*
X961139Y253100D03*
X964639D03*
X961139Y256600D03*
X964639D03*
X961630Y340840D03*
X965130D03*
X961630Y344340D03*
X965130D03*
X1093800Y115500D03*
X1090300D03*
X1092000Y270000D03*
X1088500D03*
X1043300Y490900D03*
X1046800D03*
X1105456Y278241D03*
X1101956D03*
X1107700Y304100D03*
X1111200D03*
X1107756Y310241D03*
X1111256D03*
X1107756Y307241D03*
X1111256D03*
X1107756Y286141D03*
X1111256D03*
X1111300Y294500D03*
X1107800D03*
X1111300Y298100D03*
X1107800D03*
X1111300Y301100D03*
X1107800D03*
X1107756Y289341D03*
X1111256D03*
X1107756Y282941D03*
X1111256D03*
X1165400Y257726D03*
X1161900D03*
X1165522Y261143D03*
X1162022D03*
X1271550Y111670D03*
X1275050D03*
X1271550Y125857D03*
X1275050D03*
X1271550Y129670D03*
X1275050D03*
X1271139Y117373D03*
X1274639D03*
X1275050Y107918D03*
X1271550D03*
X1264550Y107670D03*
X1268050D03*
Y129670D03*
X1264550D03*
X1268050Y125670D03*
X1264550D03*
X1268050Y111670D03*
X1264550D03*
X1252300Y130700D03*
X1255800D03*
X1252300Y134700D03*
X1255800D03*
X1248700Y473700D03*
X1245200D03*
X1245300Y477300D03*
X1248800D03*
X1330100Y71510D03*
X1333600D03*
X1330100Y68000D03*
X1333600D03*
X1291524Y214952D03*
X1288024D03*
X1303072Y249560D03*
X1299572D03*
X1303171Y245893D03*
X1299671D03*
X1299750Y241500D03*
X1303250D03*
X1288000Y219000D03*
X1291500D03*
X1287670Y231199D03*
X1291170D03*
X1291000Y237500D03*
X1287500D03*
Y243500D03*
X1291000D03*
X1303040Y264840D03*
X1299540D03*
X1303040Y260840D03*
X1299540D03*
X1299589Y257102D03*
X1303089D03*
X1303072Y252660D03*
X1299572D03*
X1287500Y240500D03*
X1291000D03*
X1298000Y219000D03*
X1294500D03*
X1341500Y329100D03*
Y332700D03*
Y325600D03*
X1340969Y354526D03*
X1337469D03*
X1281350Y488700D03*
X1284850D03*
X1367089Y2676D03*
X1370589D03*
X1367400Y34700D03*
X1370900D03*
X1382080Y328782D03*
X1385580D03*
X1345000Y329100D03*
Y332700D03*
Y325600D03*
X1346800Y340800D03*
X1343300D03*
X1385300Y341500D03*
X1381800D03*
X1385850Y286700D03*
X1389350D03*
X1385850Y283600D03*
X1389350D03*
X1388750Y293500D03*
X1392250D03*
X1385850Y289700D03*
X1389350D03*
X1395512Y339812D03*
X1399012D03*
X1385300Y332000D03*
X1381800D03*
X1386300Y338400D03*
X1382800D03*
X1386300Y335200D03*
X1382800D03*
X1343300Y347800D03*
X1346800D03*
Y344300D03*
X1343300D03*
X1381800Y344500D03*
X1385300D03*
X1385900Y353803D03*
X1382400D03*
X1381780Y356848D03*
X1385280D03*
X1385300Y347518D03*
X1381800D03*
X1359649Y358155D03*
X1356149D03*
X1369707Y393568D03*
X1373207D03*
X1385920Y350658D03*
X1382420D03*
X1358300Y443800D03*
X1361800D03*
X1391341Y498523D03*
X1394841D03*
X1391341Y494223D03*
X1394841D03*
X1388841Y482923D03*
X1392341D03*
X1388841Y487323D03*
X1392341D03*
X1371041Y497423D03*
X1374541D03*
X1368941Y482123D03*
X1372441D03*
X1371041Y493023D03*
X1374541D03*
X1368841Y486523D03*
X1372341D03*
X1354871Y512287D03*
X1351371D03*
X1394841Y498523D03*
X1398341D03*
X1394841Y494223D03*
X1398341D03*
X1392341Y482923D03*
X1395841D03*
X1392341Y487323D03*
X1395841D03*
X1372341Y486523D03*
X1375841D03*
X1374541Y493023D03*
X1378041D03*
X1374541Y497423D03*
X1378041D03*
X1372441Y482123D03*
X1375941D03*
X1371400Y581556D03*
X1374900D03*
X1370600Y613100D03*
X1374100D03*
X1460577Y163412D03*
X1464077D03*
Y159912D03*
X1460577D03*
X1419511Y176559D03*
X1423011D03*
Y173059D03*
X1419511D03*
Y170059D03*
X1423011D03*
X1419511Y166559D03*
X1423011D03*
Y163559D03*
X1419511D03*
Y179559D03*
X1423011D03*
X1419511Y186059D03*
X1423011D03*
X1419511Y183059D03*
X1423011D03*
X1452659Y188296D03*
X1456159D03*
X1438072Y189932D03*
X1434572D03*
X1458500Y252000D03*
X1462000D03*
X1435500Y311400D03*
X1439000D03*
X1435500Y308400D03*
X1439000D03*
X1435500Y305400D03*
X1439000D03*
X1434700Y315100D03*
X1438200D03*
X1453811Y369748D03*
X1457311D03*
X1449564Y362601D03*
X1453064D03*
X1451000Y448000D03*
X1454500D03*
X1451000Y437000D03*
X1454500D03*
X1451000Y442500D03*
X1454500D03*
X1435500Y437000D03*
X1439000D03*
X1435500Y448000D03*
X1439000D03*
X1435500Y453500D03*
X1439000D03*
X1451000Y431500D03*
X1454500D03*
X1435500Y442500D03*
X1439000D03*
X1444614Y482523D03*
X1448114D03*
X1444614Y478123D03*
X1448114D03*
X1444641Y489723D03*
X1448141D03*
X1444641Y494123D03*
X1448141D03*
X1421014Y482323D03*
X1424514D03*
X1421014Y477923D03*
X1424514D03*
X1420841Y494323D03*
X1424341D03*
X1420841Y489923D03*
X1424341D03*
X1424514Y477923D03*
X1428014D03*
X1448141Y489723D03*
X1451641D03*
X1448141Y494123D03*
X1451641D03*
X1448114Y482523D03*
X1451614D03*
X1448114Y478123D03*
X1451614D03*
X1424341Y489923D03*
X1427841D03*
X1424341Y494323D03*
X1427841D03*
X1424514Y482323D03*
X1428014D03*
X1436060Y541455D03*
X1432560D03*
X1436060Y544955D03*
X1432560D03*
X1501900Y12541D03*
X1505400D03*
X1526000Y64500D03*
X1520106Y93976D03*
X1516606D03*
X1497500Y76000D03*
X1494000D03*
X1497500Y79500D03*
X1494000D03*
X1526337Y136439D03*
X1522837D03*
X1520106Y97976D03*
X1516606D03*
X1521071Y104358D03*
X1517571D03*
X1521071Y108358D03*
X1517571D03*
X1520610Y120361D03*
X1517110D03*
X1520610Y116361D03*
X1517110D03*
X1472072Y142112D03*
X1468572D03*
X1520250Y215000D03*
X1516750D03*
X1521500Y194500D03*
X1518000D03*
X1523500Y189000D03*
X1520000D03*
Y186000D03*
X1523500D03*
X1518979Y179889D03*
X1522479D03*
X1494000Y194000D03*
X1490500D03*
X1480250Y180000D03*
X1476750D03*
X1477442Y190269D03*
X1473942D03*
Y187269D03*
X1477442D03*
X1468300Y181400D03*
X1471800D03*
X1470223Y156988D03*
X1473723D03*
X1508750Y177000D03*
X1505250D03*
X1508750Y174000D03*
X1505250D03*
X1473123Y163088D03*
X1476623D03*
X1473123Y160088D03*
X1476623D03*
X1469700Y211850D03*
X1473200D03*
X1468300Y184400D03*
X1471800D03*
X1480250Y176800D03*
X1476750D03*
X1515312Y231532D03*
X1518812D03*
X1515250Y237000D03*
X1518750D03*
X1470729Y240547D03*
X1467229D03*
X1467750Y220000D03*
X1471250D03*
X1467750Y223500D03*
X1471250D03*
X1467750Y227000D03*
X1471250D03*
X1525422Y227625D03*
Y230625D03*
X1526610Y336680D03*
Y333680D03*
X1480500Y323500D03*
X1477000D03*
X1526660Y315900D03*
X1487000Y322400D03*
X1490500D03*
X1498430Y311510D03*
X1501930D03*
X1513060Y319170D03*
X1509560D03*
X1503519Y283694D03*
X1507019D03*
X1506996Y280694D03*
X1503496D03*
X1487000Y325500D03*
X1490500D03*
X1522810Y327640D03*
X1519310D03*
X1479200Y401900D03*
X1475700D03*
X1479000Y394900D03*
X1475500D03*
X1470100Y360500D03*
X1466600D03*
X1470200Y357500D03*
X1466700D03*
X1469750Y369500D03*
X1466250D03*
X1469750Y366500D03*
X1466250D03*
X1475755Y376254D03*
X1479255D03*
X1475500Y398400D03*
X1479000D03*
X1502302Y410686D03*
X1505802D03*
X1524100Y494123D03*
X1527600D03*
X1511000Y526000D03*
X1507500D03*
X1474300Y615500D03*
X1477800D03*
X1508600Y616416D03*
X1512100D03*
X1508600Y623110D03*
X1512100D03*
X1586600Y-13300D03*
Y-9600D03*
X1555450Y81200D03*
X1558950D03*
X1529500Y64500D03*
X1552050Y78000D03*
X1555550D03*
X1548850Y81200D03*
X1552350D03*
X1587100Y91000D03*
X1583600D03*
X1534436Y95154D03*
X1537936D03*
X1534436Y85354D03*
X1537936D03*
X1534436Y88754D03*
X1537936D03*
X1534436Y91954D03*
X1537936D03*
X1536000Y64500D03*
X1532500D03*
X1534889Y34238D03*
X1531389D03*
X1536000Y68000D03*
X1532500D03*
X1585000Y137000D03*
X1581500D03*
X1584450Y155600D03*
X1580950D03*
Y152600D03*
X1584450D03*
Y146100D03*
X1580950D03*
Y149200D03*
X1584450D03*
X1577271Y101142D03*
X1573771D03*
X1563502Y117500D03*
X1560002D03*
X1553500D03*
X1557000D03*
X1543169Y143954D03*
X1539669D03*
X1584599Y143038D03*
X1581099D03*
X1584599Y140038D03*
X1581099D03*
X1545500Y112500D03*
X1549000D03*
X1545500Y109000D03*
X1549000D03*
X1534436Y101554D03*
X1537936D03*
X1534436Y98354D03*
X1537936D03*
X1534750Y152065D03*
X1538250D03*
X1534750Y148565D03*
X1538250D03*
X1534750Y155565D03*
X1538250D03*
X1580750Y166000D03*
X1584250D03*
X1584099Y162838D03*
X1580599D03*
X1584099Y159838D03*
X1580599D03*
X1580750Y169000D03*
X1584250D03*
X1578920Y190920D03*
X1575420D03*
X1556000Y257250D03*
X1552500D03*
X1556008Y260918D03*
X1552508D03*
X1528750Y241500D03*
X1532250D03*
X1536000Y260500D03*
X1532500D03*
X1528922Y227625D03*
Y230625D03*
X1532650Y253713D03*
X1536150D03*
X1566817Y243681D03*
X1570317D03*
X1552500Y264000D03*
X1556000D03*
X1555500Y247000D03*
X1552000D03*
X1555500Y250500D03*
X1552000D03*
X1587971Y311952D03*
X1530110Y336680D03*
Y333680D03*
X1530160Y315900D03*
X1576100Y292000D03*
X1572600D03*
X1562500Y296050D03*
X1566000D03*
X1589250Y379500D03*
Y385500D03*
Y382500D03*
Y388500D03*
X1546032Y352846D03*
X1549532D03*
Y347696D03*
X1546032D03*
X1585352Y366117D03*
X1588852D03*
X1585352Y369117D03*
X1588852D03*
X1574250Y418000D03*
X1577750D03*
X1547269Y448438D03*
X1543769D03*
X1546972Y453999D03*
X1543472D03*
X1535200Y494123D03*
X1531700D03*
X1583255Y502596D03*
X1579755D03*
X1583255Y497596D03*
X1579755D03*
X1576456Y491096D03*
X1572956D03*
X1576456Y494596D03*
X1572956D03*
X1588300Y583000D03*
X1574569Y589228D03*
X1578069D03*
X1581000Y603500D03*
X1584500D03*
X1581000Y600500D03*
X1584500D03*
X1557039Y614627D03*
X1560539D03*
X1538110Y598430D03*
X1541610D03*
X1548371Y594310D03*
X1551871D03*
X1552172Y604536D03*
X1548672D03*
X1538430Y604180D03*
X1541930D03*
X1551871Y597810D03*
X1548371D03*
X1551871Y601310D03*
X1548371D03*
X1549075Y619000D03*
X1552575D03*
X1590100Y-13300D03*
X1627250Y17000D03*
X1630750D03*
X1634250D03*
X1637750D03*
X1613250Y18000D03*
X1609750D03*
X1605000Y-1100D03*
X1608500D03*
X1590100Y-9600D03*
X1616250Y17000D03*
X1619750D03*
X1624750Y72000D03*
X1628250D03*
X1614250Y78000D03*
X1610750D03*
X1628500Y80300D03*
X1632000D03*
X1624750Y69000D03*
X1628250D03*
X1603550Y58200D03*
X1607050D03*
X1609450Y34500D03*
X1605950D03*
X1613550Y34700D03*
X1617050D03*
X1617727Y46763D03*
X1621227D03*
X1622750Y43311D03*
X1619250D03*
X1645000Y35500D03*
X1648500D03*
X1609099Y86038D03*
X1612599D03*
X1611059Y46684D03*
X1614559D03*
X1598439Y128600D03*
X1601939D03*
X1606500Y110000D03*
X1603000D03*
X1604500Y107000D03*
X1601000D03*
X1599401Y138165D03*
X1595901D03*
X1599400Y135092D03*
X1595900D03*
X1594600Y131600D03*
X1598100D03*
X1595300Y121500D03*
X1591800D03*
X1595250Y118500D03*
X1591750D03*
X1594150Y115500D03*
X1590650D03*
X1641854Y138592D03*
X1645354D03*
X1635480Y146470D03*
X1638980D03*
X1646111Y150750D03*
X1642611D03*
X1645601Y144750D03*
X1649101D03*
X1639250Y115500D03*
X1635750D03*
X1648090Y118640D03*
X1616750Y131500D03*
X1620250D03*
X1626750Y137500D03*
X1623250D03*
X1616592Y156055D03*
X1620092D03*
X1616599Y137538D03*
X1620099D03*
X1622250Y109500D03*
X1618750D03*
X1622750Y96000D03*
X1626250D03*
X1622750Y99500D03*
X1626250D03*
X1622750Y103000D03*
X1626250D03*
X1608250Y96000D03*
X1611750D03*
X1622888Y116340D03*
X1619388D03*
X1616498Y122472D03*
X1619998D03*
X1645597Y147750D03*
X1649097D03*
X1623700Y143900D03*
X1620200D03*
X1622791Y113140D03*
X1619291D03*
X1644950Y189600D03*
X1648450D03*
Y192600D03*
X1644950D03*
X1619846Y188276D03*
X1623346D03*
X1619781Y191683D03*
X1623281D03*
X1599740Y200550D03*
X1596240D03*
X1629380Y179436D03*
X1632880D03*
X1591471Y311952D03*
X1592750Y379500D03*
Y385500D03*
Y382500D03*
Y388500D03*
X1626200Y352050D03*
X1629700D03*
X1591852Y366117D03*
X1595352D03*
X1591852Y372117D03*
X1595352D03*
X1591852Y369117D03*
X1595352D03*
X1605250Y430000D03*
X1608750D03*
X1622783Y419548D03*
X1626283D03*
X1619500Y494000D03*
X1616000D03*
X1591800Y583000D03*
X1628600Y559200D03*
X1632100D03*
X1615000Y555200D03*
X1618500D03*
X1628600D03*
X1632100D03*
X1609100Y582500D03*
X1612600D03*
X1609100Y578500D03*
X1612600D03*
X1618000Y576500D03*
X1621500D03*
X1618000Y572500D03*
X1621500D03*
X1615000Y559200D03*
X1618500D03*
X1619500Y586880D03*
X1616000D03*
X1611000Y596500D03*
X1607500D03*
X1619500Y599500D03*
X1616000D03*
X1619500Y603000D03*
X1616000D03*
X1610400Y608200D03*
X1606900D03*
X1611000Y593000D03*
X1607500D03*
X1610400Y604700D03*
X1606900D03*
X1619500Y590380D03*
X1616000D03*
X1661250Y16500D03*
X1664750D03*
X1711250Y68500D03*
X1707750D03*
Y72000D03*
X1711250D03*
X1686250Y80000D03*
X1682750D03*
X1686250Y83000D03*
X1682750D03*
X1662500Y58800D03*
X1659000D03*
X1671700Y59300D03*
X1675200D03*
X1673750Y46000D03*
X1677250D03*
X1671700Y55800D03*
X1675200D03*
X1680736Y47039D03*
X1684236D03*
X1684250Y44000D03*
X1680750D03*
X1688350Y71000D03*
X1684850D03*
Y68000D03*
X1688350D03*
X1685661Y60161D03*
X1689161D03*
X1685661Y63161D03*
X1689161D03*
X1690250Y49000D03*
X1693750D03*
X1689750Y54000D03*
X1693250D03*
X1692272Y60161D03*
X1695772D03*
X1686125Y51223D03*
X1682625D03*
X1682638Y54311D03*
X1686138D03*
X1682750Y86000D03*
X1686250D03*
X1682750Y89000D03*
X1686250D03*
Y92000D03*
X1682750D03*
X1686250Y95000D03*
X1682750D03*
X1702749Y69233D03*
X1699249D03*
X1651590Y118640D03*
X1657500Y128000D03*
X1654000D03*
X1656599Y189608D03*
X1653099D03*
X1660679Y179278D03*
X1657179D03*
Y175778D03*
X1660679D03*
X1653099Y192608D03*
X1656599D03*
X1711535Y172070D03*
X1708035D03*
X1710811Y165400D03*
X1711506Y168970D03*
X1708006D03*
X1658800Y327300D03*
X1662300D03*
X1705683Y580727D03*
X1709183D03*
Y584727D03*
X1705683D03*
X1699780Y558817D03*
X1696280D03*
X1699780Y555517D03*
X1696280D03*
X1667680Y587000D03*
X1664180D03*
X1656000Y578500D03*
X1659500D03*
X1656000Y582000D03*
X1659500D03*
X1703500Y604500D03*
X1707000D03*
X1703500Y595500D03*
X1707000D03*
X1703500Y600000D03*
X1707000D03*
X1659500Y597500D03*
X1656000D03*
X1659500Y594000D03*
X1656000D03*
X1659500Y613500D03*
X1656000D03*
X1659500Y610000D03*
X1656000D03*
X1667500Y606000D03*
X1664000D03*
X1667500Y602500D03*
X1664000D03*
X1667680Y590500D03*
X1664180D03*
X1768100Y31700D03*
X1771600D03*
X1759900Y71300D03*
X1763400D03*
X1773750Y94500D03*
X1770250D03*
Y89500D03*
X1773750D03*
X1763300Y68300D03*
X1759800D03*
X1731960Y83830D03*
X1728460D03*
X1743000Y51600D03*
X1739500D03*
Y57800D03*
X1743000D03*
X1756879Y87674D03*
X1760379D03*
X1756961Y93081D03*
X1760461D03*
X1737589Y63639D03*
X1734089D03*
X1723681Y89100D03*
X1727181D03*
X1772211Y67650D03*
Y70650D03*
X1743000Y54700D03*
X1739500D03*
X1770250Y99500D03*
X1773750D03*
X1751779Y151165D03*
X1748279D03*
X1730289Y130319D03*
X1726789D03*
X1730289Y126381D03*
X1726789D03*
X1761035Y116600D03*
X1764535D03*
X1770250Y104500D03*
X1773750D03*
X1761035Y113400D03*
X1764535D03*
X1725250Y191500D03*
X1728750D03*
X1714311Y165400D03*
X1734930Y228440D03*
X1738430D03*
X1745920Y228410D03*
X1742420D03*
X1759400Y243400D03*
X1755900D03*
X1759400Y246400D03*
X1755900D03*
X1765000Y517000D03*
X1768500D03*
X1774000Y555500D03*
X1770500D03*
X1741200Y559200D03*
X1744700D03*
X1773900Y562450D03*
X1770400D03*
X1769000Y581900D03*
X1772500D03*
X1769000Y578900D03*
X1772500D03*
X1746292Y578251D03*
X1742792D03*
X1769050Y588100D03*
X1772550D03*
X1745200Y555363D03*
X1741700D03*
X1769050Y585000D03*
X1772550D03*
X1746269Y581351D03*
X1742769D03*
X1769000Y591100D03*
X1772500D03*
X1768397Y613578D03*
X1771897D03*
X1730232Y618712D03*
X1726732D03*
X1832250Y17500D03*
X1828750D03*
X1835250D03*
X1784415Y15168D03*
X1780915D03*
X1784415Y18168D03*
X1780915D03*
X1804500Y16600D03*
X1801000D03*
X1797000D03*
X1793500D03*
X1782200Y21700D03*
X1778700D03*
X1819930Y52029D03*
X1823430D03*
X1775711Y67650D03*
Y70650D03*
X1804814Y84623D03*
X1801314D03*
X1819136Y42120D03*
X1822636D03*
X1792127Y125981D03*
X1788627D03*
Y122981D03*
X1792127D03*
X1814900Y137600D03*
X1811400D03*
Y140600D03*
X1814900D03*
X1783300Y519100D03*
X1786800D03*
X1809052Y523001D03*
X1812552D03*
X1821052D03*
X1817552D03*
X1824750Y498000D03*
X1828250D03*
X1807600Y515600D03*
X1804100D03*
X1825552Y537501D03*
X1822052D03*
X1825552Y541001D03*
X1822052D03*
X1819552Y581301D03*
X1816052D03*
X1786200Y574700D03*
X1789700D03*
Y580900D03*
X1786200D03*
X1805100Y567500D03*
X1801600D03*
X1822000Y576000D03*
X1818500D03*
X1786200Y577800D03*
X1789700D03*
X1812000Y606000D03*
X1808500D03*
X1838750Y17500D03*
X1873336Y22480D03*
X1869836D03*
X1873336Y18980D03*
X1869836D03*
X1883993Y13300D03*
X1880493D03*
X1883951Y9897D03*
X1880451D03*
X1845197Y27000D03*
X1841697D03*
X1848486Y29680D03*
X1851986D03*
X1848386Y17980D03*
X1851886D03*
X1876993Y13300D03*
X1880493D03*
X1876951Y9897D03*
X1880451D03*
X1862539Y78537D03*
X1866039D03*
Y75138D03*
X1862539D03*
X1856163Y150948D03*
X1859663D03*
X1863500Y151000D03*
X1867000D03*
X1893150Y155600D03*
X1889650D03*
X1892050Y152100D03*
X1888550D03*
X1885750Y130500D03*
X1889250D03*
X1871290Y121480D03*
X1867790D03*
X1871290Y117980D03*
X1867790D03*
X1891250Y119000D03*
X1894750D03*
X1891290Y115580D03*
X1894790D03*
X1897000Y209200D03*
X1847000Y216500D03*
X1850500D03*
X1893200Y170900D03*
X1889700D03*
X1893200Y167700D03*
X1889700D03*
X1893250Y174500D03*
X1889750D03*
X1892750Y159100D03*
X1889250D03*
X1896735Y231622D03*
Y228622D03*
X1892963Y231387D03*
X1889463D03*
X1892963Y228387D03*
X1889463D03*
X1896735Y225622D03*
X1847000Y222000D03*
X1850500D03*
X1847000Y240000D03*
X1850500D03*
X1847000Y243000D03*
X1850500D03*
X1847000Y246000D03*
X1850500D03*
X1847000Y228000D03*
X1850500D03*
X1847000Y237000D03*
X1850500D03*
X1847000Y225000D03*
X1850500D03*
Y234000D03*
X1847000D03*
X1850500Y231000D03*
X1847000D03*
X1858500Y445100D03*
X1855000D03*
Y441500D03*
X1858500D03*
X1895200Y445300D03*
X1898000Y451000D03*
X1894500D03*
X1865847Y500954D03*
X1869347D03*
X1865799Y504018D03*
X1869299D03*
X1862700Y491650D03*
X1859200D03*
X1854550Y505510D03*
X1858050D03*
X1862700Y488500D03*
X1859200D03*
X1896154Y563968D03*
Y560968D03*
Y566968D03*
X1894654Y569968D03*
X1855750Y545500D03*
X1852250D03*
Y542500D03*
X1855750D03*
X1871500Y579500D03*
X1875000D03*
X1872146Y533140D03*
X1875646D03*
X1869310D03*
X1865810D03*
X1852500Y530700D03*
X1849000D03*
X1845750Y542500D03*
X1849250D03*
X1841500Y552600D03*
X1838000D03*
X1861538Y572746D03*
X1865038D03*
X1859187Y534585D03*
X1862687D03*
X1859217Y531331D03*
X1862717D03*
X1913143Y-19572D03*
X1909643D03*
X1909661Y-16368D03*
X1913161D03*
X1908166Y67073D03*
X1904666D03*
X1901661Y67193D03*
X1898161D03*
X1920500Y71500D03*
X1924000D03*
X1898143Y70589D03*
X1901643D03*
X1904736Y70607D03*
X1908236D03*
X1959619Y136676D03*
X1956321Y149724D03*
D03*
X1952821D03*
X1920100Y143100D03*
X1923600D03*
X1914700Y137600D03*
X1918200D03*
X1942637Y103377D03*
X1939137D03*
X1951341Y187424D03*
X1954841D03*
X1951318Y181882D03*
X1954818D03*
X1912850Y196300D03*
X1909350D03*
X1900500Y209200D03*
X1930449Y183722D03*
X1926949D03*
X1930341Y188701D03*
X1926841D03*
X1919150Y163100D03*
X1922650D03*
X1933250Y157600D03*
X1936750D03*
X1898250Y191000D03*
X1901750D03*
X1918750Y171600D03*
X1922250D03*
X1918474Y175140D03*
X1921974D03*
X1902250Y187500D03*
X1898750D03*
X1900235Y231622D03*
Y228622D03*
Y225622D03*
X1917336Y231924D03*
X1913836D03*
X1925665Y239441D03*
X1922165D03*
X1917356Y228756D03*
X1913856D03*
X1925660Y236318D03*
X1922160D03*
X1913970Y239458D03*
X1910470D03*
X1913959Y236258D03*
X1910459D03*
X1910500Y445800D03*
X1914000D03*
X1926500D03*
X1923000D03*
X1898700Y445300D03*
X1905000Y451000D03*
X1901500D03*
X1929860Y486480D03*
X1933360D03*
X1934150Y475400D03*
X1930650D03*
X1934150Y478400D03*
X1930650D03*
X1944710Y484520D03*
X1941210D03*
X1931285Y583000D03*
X1927785D03*
X1931285Y579500D03*
X1927785D03*
X1931285Y575500D03*
X1927785D03*
X1931285Y572000D03*
X1927785D03*
X1899654Y563968D03*
Y560968D03*
Y566968D03*
X1898154Y569968D03*
X1921500Y549900D03*
X1918000D03*
X1921000Y554400D03*
X1917500D03*
X1927750Y611550D03*
X1931250D03*
X1929740Y594760D03*
X1926240D03*
Y591260D03*
X1929740D03*
X1921250Y596900D03*
X1917750D03*
Y600400D03*
X1921250D03*
X1963119Y136676D03*
X1966619D03*
X1963119D03*
X1959821Y149724D03*
X1968249Y149881D03*
X1971749D03*
X1965973Y169460D03*
X1969473D03*
X1963500Y518200D03*
X1967000D03*
X1966500Y545500D03*
X1963000D03*
X1966500Y540500D03*
X1963000D03*
X1971000Y603100D03*
X1967500D03*
G54D80*
X1229071Y340046D03*
G54D128*
X1629618Y122418D03*
X1772903Y112612D03*
G54D62*
X589349Y335730D03*
G54D71*
X649591Y138067D03*
X652282Y184964D03*
G54D174*
G01X430749Y-124922D02*
G02I-12000J0D01*
G01X425599D02*
G02I-6850J0D01*
G01X434749D02*
X402749D01*
G01X434749Y-140922D02*
Y-220922D01*
G01D02*
X1729349D01*
G01X434749Y-176422D02*
X1729349D01*
G01X418749Y-140922D02*
Y-108922D01*
G01X434749Y-140922D02*
X1729349D01*
G01X941849D02*
Y-220922D01*
G01X1079349Y-140922D02*
Y-220922D01*
G01X1194349Y-140922D02*
Y-220922D01*
G01X1361849Y-140922D02*
Y-220922D01*
G01X1531849Y-140922D02*
Y-220922D01*
G01X1729349Y-140922D02*
Y-220922D01*
G01X1757349Y-124922D02*
G02I-12000J0D01*
G01X1752199D02*
G02I-6850J0D01*
G01X1745349Y-140922D02*
Y-108922D01*
G01X1761349Y-124922D02*
X1729349D01*
G54D156*
X1813505Y600103D03*
X1807599D03*
G54D147*
X1752480Y557738D03*
X1754448D03*
X1756417D03*
X1758386D03*
X1760354D03*
X1806115Y529899D03*
X1810052D03*
X1808083D03*
X1812021D03*
X1813989D03*
G54D165*
X1915031Y208449D03*
X1922431D03*
G54D90*
X1263600Y483540D03*
X1281600D03*
X1263600Y478420D03*
X1281600D03*
X1263600Y480980D03*
X1281600D03*
X1263600Y475860D03*
X1281600D03*
G54D27*
X28700Y484000D03*
Y480064D03*
X20600D03*
Y484000D03*
X28700Y482032D03*
Y478096D03*
X20600Y482032D03*
Y478096D03*
G54D129*
X1629618Y128018D03*
X1772903Y118212D03*
G54D18*
X42800Y35300D03*
Y56300D03*
Y77300D03*
X43100Y568100D03*
X42900Y547900D03*
X43100Y588600D03*
Y608600D03*
X70800Y35300D03*
Y56300D03*
Y77300D03*
X71100Y568100D03*
X70900Y547900D03*
X71100Y588600D03*
Y608600D03*
X150000Y267500D03*
Y246500D03*
Y224500D03*
Y288500D03*
Y310500D03*
Y330500D03*
X151574Y396363D03*
X150000Y352000D03*
X151574Y376363D03*
X178000Y267500D03*
Y246500D03*
Y224500D03*
Y288500D03*
Y310500D03*
Y330500D03*
X179574Y396363D03*
X178000Y352000D03*
X179574Y376363D03*
X568500Y483500D03*
X596500D03*
X649500Y217500D03*
Y238800D03*
X667900Y562300D03*
X730000Y195700D03*
X677500Y217500D03*
Y238800D03*
X695900Y562300D03*
X758000Y195700D03*
X802108Y246500D03*
X830108D03*
X802108Y224500D03*
X830108D03*
X802108Y267500D03*
X830108D03*
X802108Y310500D03*
X830108D03*
X802108Y288500D03*
X830108D03*
X802108Y330500D03*
X830108D03*
X801182Y376363D03*
X829182D03*
X801182Y396363D03*
X829182D03*
X802108Y352800D03*
X830108D03*
X1343000Y-8000D03*
X1315000D03*
X1343000Y13000D03*
X1315000D03*
X1323000Y371000D03*
Y391000D03*
X1347600Y431000D03*
X1323000Y411000D03*
X1339081Y473466D03*
X1311081D03*
X1340172Y491683D03*
X1312172D03*
X1343000Y592000D03*
X1315000D03*
X1335500Y556500D03*
X1307500D03*
X1334300Y533100D03*
X1306300D03*
X1343000Y612000D03*
X1315000D03*
X1356000Y137000D03*
X1384000D03*
X1377700Y183700D03*
X1349700D03*
X1351000Y371000D03*
Y391000D03*
X1375600Y431000D03*
X1351000Y411000D03*
X1871725Y87256D03*
X1899725D03*
X1897200Y463700D03*
X1925200D03*
G54D63*
X601049Y345981D03*
G54D138*
X1712642Y99814D03*
G54D81*
X1223453Y336318D03*
G54D45*
X80539Y320948D03*
X65800Y364500D03*
X110758Y122310D03*
X1609800Y82000D03*
X1741100Y61300D03*
X1773350Y567650D03*
Y571695D03*
X1883066Y473995D03*
G54D72*
X634264Y197080D03*
G54D36*
X68000Y232300D03*
G54D54*
X346748Y492120D03*
X367615Y491120D03*
X1037657Y487300D03*
G54D175*
G01X548049Y-193422D02*
Y-210922D01*
G01X543027Y-193422D02*
X553071D01*
G01X565549Y-199256D02*
Y-210922D01*
G01Y-194589D02*
X565112Y-194297D01*
Y-193714D01*
X565549Y-193422D01*
X565986Y-193714D01*
Y-194297D01*
X565549Y-194589D01*
G01X583049Y-210922D02*
X581739Y-210630D01*
X580429Y-209464D01*
X579555Y-207422D01*
X579119Y-205089D01*
X579555Y-202755D01*
X580429Y-200714D01*
X581739Y-199547D01*
X583049Y-199256D01*
X584359Y-199547D01*
X585669Y-200714D01*
X586542Y-202755D01*
X586761Y-205089D01*
X586542Y-207422D01*
X585669Y-209464D01*
X584359Y-210630D01*
X583049Y-210922D01*
G01X597492Y-215297D02*
X599021Y-216464D01*
X600767Y-216755D01*
X602295Y-216464D01*
X603606Y-215006D01*
X604479Y-212964D01*
Y-199256D01*
G01Y-201589D02*
X603606Y-200422D01*
X602295Y-199547D01*
X600767Y-199256D01*
X599021Y-199839D01*
X597929Y-201005D01*
X597055Y-203047D01*
X596619Y-205089D01*
X596837Y-206839D01*
X597711Y-208881D01*
X599021Y-210339D01*
X600767Y-210922D01*
X602077Y-210630D01*
X603606Y-209464D01*
X604479Y-208298D01*
G01X621979Y-210922D02*
Y-199256D01*
G01Y-201297D02*
X621106Y-200131D01*
X619795Y-199547D01*
X618267Y-199256D01*
X616739Y-199839D01*
X615429Y-201005D01*
X614555Y-202755D01*
X614119Y-205089D01*
X614555Y-207422D01*
X615429Y-209172D01*
X616739Y-210339D01*
X618267Y-210922D01*
X619795Y-210630D01*
X621106Y-209756D01*
X621979Y-208589D01*
G01X648682Y-210922D02*
Y-193422D01*
X653922D01*
X655669Y-194297D01*
X656979Y-196339D01*
X657416Y-198672D01*
X656979Y-201005D01*
X655887Y-202755D01*
X653922Y-203631D01*
X648682D01*
G01X674479Y-210922D02*
Y-199256D01*
G01Y-201297D02*
X673606Y-200131D01*
X672295Y-199547D01*
X670767Y-199256D01*
X669239Y-199839D01*
X667929Y-201005D01*
X667055Y-202755D01*
X666619Y-205089D01*
X667055Y-207422D01*
X667929Y-209172D01*
X669239Y-210339D01*
X670767Y-210922D01*
X672295Y-210630D01*
X673606Y-209756D01*
X674479Y-208589D01*
G01X684774Y-208881D02*
X685866Y-210047D01*
X687394Y-210922D01*
X688704D01*
X690014Y-210339D01*
X690887Y-209464D01*
X691324Y-208298D01*
X691106Y-206547D01*
X690232Y-205672D01*
X686302Y-203922D01*
X685429Y-201880D01*
X685866Y-200422D01*
X686739Y-199547D01*
X688049Y-199256D01*
X689359Y-199547D01*
X690669Y-200422D01*
G01X702274Y-208881D02*
X703366Y-210047D01*
X704894Y-210922D01*
X706204D01*
X707514Y-210339D01*
X708387Y-209464D01*
X708824Y-208298D01*
X708606Y-206547D01*
X707732Y-205672D01*
X703802Y-203922D01*
X702929Y-201880D01*
X703366Y-200422D01*
X704239Y-199547D01*
X705549Y-199256D01*
X706859Y-199547D01*
X708169Y-200422D01*
G01X735746Y-210922D02*
Y-193422D01*
X740112D01*
X741859Y-194297D01*
X743169Y-195464D01*
X744261Y-197213D01*
X745134Y-199256D01*
X745352Y-202172D01*
X745134Y-205089D01*
X744261Y-207131D01*
X743169Y-208881D01*
X741859Y-210047D01*
X740112Y-210922D01*
X735746D01*
G01X752590Y-193422D02*
X758049Y-210922D01*
X763508Y-193422D01*
G01X775549D02*
Y-210922D01*
G01X770527Y-193422D02*
X780571D01*
G01X804872Y-210922D02*
Y-193422D01*
X810549Y-208005D01*
X816226Y-193422D01*
Y-210922D01*
G01X829795Y-201589D02*
X830669Y-200714D01*
X831324Y-199256D01*
X831761Y-197213D01*
X831324Y-195464D01*
X830451Y-194297D01*
X828922Y-193422D01*
X823027D01*
Y-210922D01*
X830232D01*
X831761Y-209756D01*
X832634Y-208005D01*
X833071Y-205964D01*
X832634Y-203922D01*
X831324Y-202172D01*
X829795Y-201589D01*
X823027D01*
G01X647372Y-165922D02*
Y-148422D01*
X653049Y-163005D01*
X658726Y-148422D01*
Y-165922D01*
G01X670549D02*
X669239Y-165630D01*
X667929Y-164464D01*
X667055Y-162422D01*
X666619Y-160089D01*
X667055Y-157755D01*
X667929Y-155714D01*
X669239Y-154547D01*
X670549Y-154256D01*
X671859Y-154547D01*
X673169Y-155714D01*
X674042Y-157755D01*
X674261Y-160089D01*
X674042Y-162422D01*
X673169Y-164464D01*
X671859Y-165630D01*
X670549Y-165922D01*
G01X691979Y-148422D02*
Y-165922D01*
G01Y-163298D02*
X691106Y-164756D01*
X689795Y-165630D01*
X688267Y-165922D01*
X686521Y-165339D01*
X685211Y-163881D01*
X684337Y-162131D01*
X684119Y-160089D01*
X684337Y-158047D01*
X685211Y-156297D01*
X686521Y-154839D01*
X688267Y-154256D01*
X689795Y-154547D01*
X690887Y-155131D01*
X691979Y-156297D01*
G01X702274Y-158047D02*
X709261D01*
X708606Y-156005D01*
X707514Y-154839D01*
X705986Y-154256D01*
X704457Y-154547D01*
X703147Y-155422D01*
X702274Y-157464D01*
X701837Y-159214D01*
Y-160964D01*
X702274Y-162714D01*
X703366Y-164464D01*
X704676Y-165630D01*
X706204Y-165922D01*
X707732Y-165339D01*
X709261Y-163589D01*
G01X723049Y-165922D02*
Y-148422D01*
G01X975549Y-210922D02*
Y-193422D01*
X972929Y-196922D01*
G01Y-210922D02*
X978169D01*
G01X988246Y-208298D02*
X989555Y-209756D01*
X991084Y-210630D01*
X993049Y-210922D01*
X995014Y-210339D01*
X996542Y-209172D01*
X997634Y-207131D01*
X997852Y-204797D01*
X997416Y-202464D01*
X996324Y-201005D01*
X994795Y-199839D01*
X993267Y-199547D01*
X991739Y-199839D01*
X989774Y-201005D01*
X990429Y-193422D01*
X996324D01*
G01X1010549Y-210922D02*
Y-193422D01*
X1007929Y-196922D01*
G01Y-210922D02*
X1013169D01*
G01X1023901Y-196339D02*
X1025211Y-194589D01*
X1026739Y-193714D01*
X1028486Y-193422D01*
X1030669Y-194005D01*
X1032197Y-195464D01*
X1032634Y-197213D01*
X1032416Y-198964D01*
X1031542Y-200422D01*
X1027176Y-203339D01*
X1025211Y-205380D01*
X1023901Y-208298D01*
X1023464Y-210922D01*
X1032634D01*
G01X1041401Y-203631D02*
X1042929Y-201589D01*
X1044239Y-200422D01*
X1045986Y-199839D01*
X1047514Y-200422D01*
X1048606Y-201589D01*
X1049479Y-203339D01*
X1049697Y-205380D01*
X1049479Y-207131D01*
X1048606Y-208881D01*
X1047295Y-210339D01*
X1045767Y-210922D01*
X1044021Y-210339D01*
X1042492Y-208589D01*
X1041619Y-205964D01*
X1041401Y-203047D01*
X1041837Y-199256D01*
X1042492Y-197213D01*
X1043584Y-195172D01*
X1045112Y-193714D01*
X1046641Y-193422D01*
X1048169Y-194005D01*
X1049261Y-195464D01*
G01X962432Y-165922D02*
Y-148422D01*
X967672D01*
X969419Y-149297D01*
X970729Y-151339D01*
X971166Y-153672D01*
X970729Y-156005D01*
X969637Y-157755D01*
X967672Y-158631D01*
X962432D01*
G01X989102Y-149881D02*
X987792Y-149005D01*
X986264Y-148422D01*
X984517D01*
X982552Y-149297D01*
X981024Y-150755D01*
X979932Y-152506D01*
X979059Y-155422D01*
X978840Y-158047D01*
X979277Y-160672D01*
X979932Y-162422D01*
X981242Y-164172D01*
X982771Y-165339D01*
X984299Y-165922D01*
X985827D01*
X987356Y-165339D01*
X988666Y-164464D01*
X989758Y-163298D01*
G01X1003545Y-156589D02*
X1004419Y-155714D01*
X1005074Y-154256D01*
X1005511Y-152213D01*
X1005074Y-150464D01*
X1004201Y-149297D01*
X1002672Y-148422D01*
X996777D01*
Y-165922D01*
X1003982D01*
X1005511Y-164756D01*
X1006384Y-163005D01*
X1006821Y-160964D01*
X1006384Y-158922D01*
X1005074Y-157172D01*
X1003545Y-156589D01*
X996777D01*
G01X1012749Y-171755D02*
X1025849D01*
G01X1031777Y-165922D02*
Y-148422D01*
X1041821Y-165922D01*
Y-148422D01*
G01X1054299Y-165922D02*
X1052552Y-165630D01*
X1051024Y-164464D01*
X1049714Y-162714D01*
X1048840Y-160672D01*
X1048404Y-158339D01*
Y-156005D01*
X1048840Y-153672D01*
X1049714Y-151630D01*
X1051024Y-149881D01*
X1052552Y-148714D01*
X1054299Y-148422D01*
X1056045Y-148714D01*
X1057574Y-149881D01*
X1058884Y-151630D01*
X1059758Y-153672D01*
X1060194Y-156005D01*
Y-158339D01*
X1059758Y-160672D01*
X1058884Y-162714D01*
X1057574Y-164464D01*
X1056045Y-165630D01*
X1054299Y-165922D01*
G01X1128099Y-210922D02*
Y-193422D01*
X1125479Y-196922D01*
G01Y-210922D02*
X1130719D01*
G01X1147345Y-201589D02*
X1148219Y-200714D01*
X1148874Y-199256D01*
X1149311Y-197213D01*
X1148874Y-195464D01*
X1148001Y-194297D01*
X1146472Y-193422D01*
X1140577D01*
Y-210922D01*
X1147782D01*
X1149311Y-209756D01*
X1150184Y-208005D01*
X1150621Y-205964D01*
X1150184Y-203922D01*
X1148874Y-202172D01*
X1147345Y-201589D01*
X1140577D01*
G01X1105140Y-148422D02*
X1110599Y-165922D01*
X1116058Y-148422D01*
G01X1132466Y-165922D02*
X1123732D01*
Y-148422D01*
X1132466D01*
G01X1128972Y-156880D02*
X1123732D01*
G01X1141232Y-165922D02*
Y-148422D01*
X1146691D01*
X1148437Y-149297D01*
X1149529Y-150464D01*
X1149966Y-152797D01*
X1149529Y-155131D01*
X1148219Y-156589D01*
X1146691Y-157464D01*
X1141232D01*
G01X1146691D02*
X1149966Y-165922D01*
G01X1163099Y-166505D02*
X1162662Y-166214D01*
Y-165630D01*
X1163099Y-165339D01*
X1163536Y-165630D01*
Y-166214D01*
X1163099Y-166505D01*
G01X1302553Y-201589D02*
X1301679Y-200714D01*
X1301024Y-199256D01*
X1300587Y-197213D01*
X1301024Y-195464D01*
X1301897Y-194297D01*
X1303426Y-193422D01*
X1309321D01*
Y-210922D01*
X1302116D01*
X1300587Y-209756D01*
X1299714Y-208005D01*
X1299277Y-205964D01*
X1299714Y-203922D01*
X1301024Y-202172D01*
X1302553Y-201589D01*
X1309321D01*
G01X1291384Y-208589D02*
X1289637Y-210047D01*
X1287672Y-210922D01*
X1285926D01*
X1284179Y-210047D01*
X1282869Y-208589D01*
X1282214Y-206547D01*
X1282651Y-204506D01*
X1283742Y-202755D01*
X1285707Y-201589D01*
X1288327Y-201005D01*
X1289856Y-199839D01*
X1290511Y-197797D01*
X1290074Y-195755D01*
X1288982Y-194297D01*
X1287454Y-193422D01*
X1285926D01*
X1284397Y-194005D01*
X1283087Y-195464D01*
G01X1274976Y-210922D02*
Y-193422D01*
X1269299Y-208005D01*
X1263622Y-193422D01*
Y-210922D01*
G01X1256602D02*
Y-193422D01*
X1252236D01*
X1250489Y-194297D01*
X1249179Y-195464D01*
X1248087Y-197213D01*
X1247214Y-199256D01*
X1246996Y-202172D01*
X1247214Y-205089D01*
X1248087Y-207131D01*
X1249179Y-208881D01*
X1250489Y-210047D01*
X1252236Y-210922D01*
X1256602D01*
G01X1238682Y-148422D02*
Y-165922D01*
X1247416D01*
G01X1264479D02*
Y-154256D01*
G01Y-156297D02*
X1263606Y-155131D01*
X1262295Y-154547D01*
X1260767Y-154256D01*
X1259239Y-154839D01*
X1257929Y-156005D01*
X1257055Y-157755D01*
X1256619Y-160089D01*
X1257055Y-162422D01*
X1257929Y-164172D01*
X1259239Y-165339D01*
X1260767Y-165922D01*
X1262295Y-165630D01*
X1263606Y-164756D01*
X1264479Y-163589D01*
G01X1273464Y-171172D02*
X1274774Y-171755D01*
X1276521Y-171172D01*
X1277612Y-170006D01*
X1278486Y-168547D01*
X1279795Y-163881D01*
X1282634Y-154256D01*
G01X1275647D02*
X1279795Y-163881D01*
G01X1292274Y-158047D02*
X1299261D01*
X1298606Y-156005D01*
X1297514Y-154839D01*
X1295986Y-154256D01*
X1294457Y-154547D01*
X1293147Y-155422D01*
X1292274Y-157464D01*
X1291837Y-159214D01*
Y-160964D01*
X1292274Y-162714D01*
X1293366Y-164464D01*
X1294676Y-165630D01*
X1296204Y-165922D01*
X1297732Y-165339D01*
X1299261Y-163589D01*
G01X1309992Y-165922D02*
Y-154256D01*
G01Y-156589D02*
X1311084Y-155422D01*
X1312176Y-154547D01*
X1313704Y-154256D01*
X1314795Y-154547D01*
X1316106Y-155422D01*
G01X1380796Y-165922D02*
Y-148422D01*
X1385162D01*
X1386909Y-149297D01*
X1388219Y-150464D01*
X1389311Y-152213D01*
X1390184Y-154256D01*
X1390402Y-157172D01*
X1390184Y-160089D01*
X1389311Y-162131D01*
X1388219Y-163881D01*
X1386909Y-165047D01*
X1385162Y-165922D01*
X1380796D01*
G01X1399824Y-158047D02*
X1406811D01*
X1406156Y-156005D01*
X1405064Y-154839D01*
X1403536Y-154256D01*
X1402007Y-154547D01*
X1400697Y-155422D01*
X1399824Y-157464D01*
X1399387Y-159214D01*
Y-160964D01*
X1399824Y-162714D01*
X1400916Y-164464D01*
X1402226Y-165630D01*
X1403754Y-165922D01*
X1405282Y-165339D01*
X1406811Y-163589D01*
G01X1417324Y-163881D02*
X1418416Y-165047D01*
X1419944Y-165922D01*
X1421254D01*
X1422564Y-165339D01*
X1423437Y-164464D01*
X1423874Y-163298D01*
X1423656Y-161547D01*
X1422782Y-160672D01*
X1418852Y-158922D01*
X1417979Y-156880D01*
X1418416Y-155422D01*
X1419289Y-154547D01*
X1420599Y-154256D01*
X1421909Y-154547D01*
X1423219Y-155422D01*
G01X1438099Y-154256D02*
Y-165922D01*
G01Y-149589D02*
X1437662Y-149297D01*
Y-148714D01*
X1438099Y-148422D01*
X1438536Y-148714D01*
Y-149297D01*
X1438099Y-149589D01*
G01X1452542Y-170297D02*
X1454071Y-171464D01*
X1455817Y-171755D01*
X1457345Y-171464D01*
X1458656Y-170006D01*
X1459529Y-167964D01*
Y-154256D01*
G01Y-156589D02*
X1458656Y-155422D01*
X1457345Y-154547D01*
X1455817Y-154256D01*
X1454071Y-154839D01*
X1452979Y-156005D01*
X1452105Y-158047D01*
X1451669Y-160089D01*
X1451887Y-161839D01*
X1452761Y-163881D01*
X1454071Y-165339D01*
X1455817Y-165922D01*
X1457127Y-165630D01*
X1458656Y-164464D01*
X1459529Y-163298D01*
G01X1469387Y-165922D02*
Y-154256D01*
G01Y-157172D02*
X1470261Y-155714D01*
X1471571Y-154547D01*
X1473317Y-154256D01*
X1474845Y-154547D01*
X1476156Y-155714D01*
X1476811Y-157755D01*
Y-165922D01*
G01X1487324Y-158047D02*
X1494311D01*
X1493656Y-156005D01*
X1492564Y-154839D01*
X1491036Y-154256D01*
X1489507Y-154547D01*
X1488197Y-155422D01*
X1487324Y-157464D01*
X1486887Y-159214D01*
Y-160964D01*
X1487324Y-162714D01*
X1488416Y-164464D01*
X1489726Y-165630D01*
X1491254Y-165922D01*
X1492782Y-165339D01*
X1494311Y-163589D01*
G01X1505042Y-165922D02*
Y-154256D01*
G01Y-156589D02*
X1506134Y-155422D01*
X1507226Y-154547D01*
X1508754Y-154256D01*
X1509845Y-154547D01*
X1511156Y-155422D01*
G01X1426729Y-193422D02*
X1431969D01*
G01X1429349D02*
Y-210922D01*
G01X1426729D02*
X1431969D01*
G01X1441390Y-193422D02*
X1446849Y-210922D01*
X1452308Y-193422D01*
G01X1464349Y-210922D02*
Y-203047D01*
X1459982Y-193422D01*
G01X1468716D02*
X1464349Y-203047D01*
G01X1551799Y-193422D02*
X1550052Y-194005D01*
X1548742Y-195464D01*
X1547869Y-197213D01*
X1547214Y-199547D01*
X1546996Y-202172D01*
X1547214Y-204797D01*
X1547869Y-207131D01*
X1548742Y-208881D01*
X1550052Y-210339D01*
X1551799Y-210922D01*
X1553545Y-210339D01*
X1554856Y-208881D01*
X1555729Y-207131D01*
X1556384Y-204797D01*
X1556602Y-202172D01*
X1556384Y-199547D01*
X1555729Y-197213D01*
X1554856Y-195464D01*
X1553545Y-194005D01*
X1551799Y-193422D01*
G01X1565151Y-196339D02*
X1566461Y-194589D01*
X1567989Y-193714D01*
X1569736Y-193422D01*
X1571919Y-194005D01*
X1573447Y-195464D01*
X1573884Y-197213D01*
X1573666Y-198964D01*
X1572792Y-200422D01*
X1568426Y-203339D01*
X1566461Y-205380D01*
X1565151Y-208298D01*
X1564714Y-210922D01*
X1573884D01*
G01X1582869Y-211505D02*
X1590729Y-193422D01*
G01X1604299Y-210922D02*
Y-193422D01*
X1601679Y-196922D01*
G01Y-210922D02*
X1606919D01*
G01X1621799Y-193422D02*
X1620052Y-194005D01*
X1618742Y-195464D01*
X1617869Y-197213D01*
X1617214Y-199547D01*
X1616996Y-202172D01*
X1617214Y-204797D01*
X1617869Y-207131D01*
X1618742Y-208881D01*
X1620052Y-210339D01*
X1621799Y-210922D01*
X1623545Y-210339D01*
X1624856Y-208881D01*
X1625729Y-207131D01*
X1626384Y-204797D01*
X1626602Y-202172D01*
X1626384Y-199547D01*
X1625729Y-197213D01*
X1624856Y-195464D01*
X1623545Y-194005D01*
X1621799Y-193422D01*
G01X1635369Y-211505D02*
X1643229Y-193422D01*
G01X1652651Y-196339D02*
X1653961Y-194589D01*
X1655489Y-193714D01*
X1657236Y-193422D01*
X1659419Y-194005D01*
X1660947Y-195464D01*
X1661384Y-197213D01*
X1661166Y-198964D01*
X1660292Y-200422D01*
X1655926Y-203339D01*
X1653961Y-205380D01*
X1652651Y-208298D01*
X1652214Y-210922D01*
X1661384D01*
G01X1674299Y-193422D02*
X1672552Y-194005D01*
X1671242Y-195464D01*
X1670369Y-197213D01*
X1669714Y-199547D01*
X1669496Y-202172D01*
X1669714Y-204797D01*
X1670369Y-207131D01*
X1671242Y-208881D01*
X1672552Y-210339D01*
X1674299Y-210922D01*
X1676045Y-210339D01*
X1677356Y-208881D01*
X1678229Y-207131D01*
X1678884Y-204797D01*
X1679102Y-202172D01*
X1678884Y-199547D01*
X1678229Y-197213D01*
X1677356Y-195464D01*
X1676045Y-194005D01*
X1674299Y-193422D01*
G01X1691799Y-210922D02*
Y-193422D01*
X1689179Y-196922D01*
G01Y-210922D02*
X1694419D01*
G01X1708862D02*
X1709299Y-207131D01*
X1709954Y-203922D01*
X1710827Y-201005D01*
X1711919Y-197797D01*
X1713666Y-193422D01*
X1704932D01*
G01X1599496Y-165922D02*
Y-148422D01*
X1603862D01*
X1605609Y-149297D01*
X1606919Y-150464D01*
X1608011Y-152213D01*
X1608884Y-154256D01*
X1609102Y-157172D01*
X1608884Y-160089D01*
X1608011Y-162131D01*
X1606919Y-163881D01*
X1605609Y-165047D01*
X1603862Y-165922D01*
X1599496D01*
G01X1625729D02*
Y-154256D01*
G01Y-156297D02*
X1624856Y-155131D01*
X1623545Y-154547D01*
X1622017Y-154256D01*
X1620489Y-154839D01*
X1619179Y-156005D01*
X1618305Y-157755D01*
X1617869Y-160089D01*
X1618305Y-162422D01*
X1619179Y-164172D01*
X1620489Y-165339D01*
X1622017Y-165922D01*
X1623545Y-165630D01*
X1624856Y-164756D01*
X1625729Y-163589D01*
G01X1639299Y-148422D02*
Y-165922D01*
G01X1636242Y-154256D02*
X1642356D01*
G01X1653524Y-158047D02*
X1660511D01*
X1659856Y-156005D01*
X1658764Y-154839D01*
X1657236Y-154256D01*
X1655707Y-154547D01*
X1654397Y-155422D01*
X1653524Y-157464D01*
X1653087Y-159214D01*
Y-160964D01*
X1653524Y-162714D01*
X1654616Y-164464D01*
X1655926Y-165630D01*
X1657454Y-165922D01*
X1658982Y-165339D01*
X1660511Y-163589D01*
G01X-7874Y-31496D02*
X-19685D01*
G01X-7874D02*
X-19685D01*
G01D02*
G03X-23622Y-35433I0J-3937D01*
G01D02*
Y-59055D01*
G01Y-35433D02*
Y-59055D01*
G01X-19685Y-31496D02*
G03X-23622Y-35433I0J-3937D01*
G01Y-59055D02*
G03X-19685Y-62992I3937J0D01*
G01D02*
X1972441D01*
G01X-19685D02*
X1972441D01*
G01X-23622Y-59055D02*
G03X-19685Y-62992I3937J0D01*
G01Y-23622D02*
X1972441D01*
G01X-19685D02*
X1972441D01*
G01X-19685D02*
X1972441D01*
G01X-19685D02*
X1972441D01*
G01X-23622Y622441D02*
Y-19685D01*
G01Y622441D02*
Y-19685D01*
G01Y622441D02*
Y-19685D01*
G01Y622441D02*
Y-19685D01*
G01D02*
G03X-19685Y-23622I3937J0D01*
G01X-23622Y-19685D02*
G03X-19685Y-23622I3937J0D01*
G01X-23622Y-19685D02*
G03X-19685Y-23622I3937J0D01*
G01X-23622Y-19685D02*
G03X-19685Y-23622I3937J0D01*
G01X1972441Y626378D02*
X-19685D01*
G01X1972441D02*
X-19685D01*
G01X1972441D02*
X-19685D01*
G01X1972441D02*
X-19685D01*
G01D02*
G03X-23622Y622441I0J-3937D01*
G01X-19685Y626378D02*
G03X-23622Y622441I0J-3937D01*
G01X-19685Y626378D02*
G03X-23622Y622441I0J-3937D01*
G01X-19685Y626378D02*
G03X-23622Y622441I0J-3937D01*
G01X-19685Y634252D02*
X-7874D01*
G01X-19685D02*
X-7874D01*
G01X-23622Y661811D02*
Y638189D01*
G01Y661811D02*
Y638189D01*
G01D02*
G03X-19685Y634252I3937J0D01*
G01X-23622Y638189D02*
G03X-19685Y634252I3937J0D01*
G01X1972441Y665748D02*
X-19685D01*
G01X1972441D02*
X-19685D01*
G01D02*
G03X-23622Y661811I0J-3937D01*
G01X-19685Y665748D02*
G03X-23622Y661811I0J-3937D01*
G01X-7874Y-31496D02*
G03Y-23622I0J3937D01*
G01Y-31496D02*
G03Y-23622I0J3937D01*
G01X22835D02*
G03Y-31496I0J-3937D01*
G01X137795D02*
X22835D01*
G01X137795D02*
X22835D01*
G01Y-23622D02*
G03Y-31496I0J-3937D01*
G01X0Y616535D02*
G03Y604724I0J-5905D01*
G01Y616535D02*
G03Y604724I0J-5905D01*
G01Y616535D02*
X2646D01*
G01X2644D02*
X0D01*
G01Y604724D02*
X2644D01*
G01X2646D02*
X0D01*
G01X2646D02*
X0D01*
G01D02*
X2644D01*
G01Y616535D02*
X0D01*
G01D02*
X2646D01*
G01X0D02*
G03Y604724I0J-5905D01*
G01Y616535D02*
G03Y604724I0J-5905D01*
G01X2646Y616535D02*
G03X7595Y618285I0J7874D01*
G01X2644Y616535D02*
G03X7593Y618285I0J7874D01*
G01X2644Y616535D02*
G03X7593Y618285I0J7874D01*
G01X7595Y602975D02*
G03X2646Y604724I-4948J-6125D01*
G01X7593Y602975D02*
G03X2644Y604724I-4948J-6125D01*
G01X7593Y602975D02*
G03X2644Y604724I-4948J-6125D01*
G01X7593Y602975D02*
G03X2644Y604724I-4948J-6125D01*
G01X7593Y602975D02*
G03X2644Y604724I-4948J-6125D01*
G01X7595Y602975D02*
G03X2646Y604724I-4948J-6125D01*
G01X2644Y616535D02*
G03X7593Y618285I0J7874D01*
G01X2644Y616535D02*
G03X7593Y618285I0J7874D01*
G01X2646Y616535D02*
G03X7595Y618285I0J7874D01*
G01Y602975D02*
G03Y618285I6186J7655D01*
G01X7593Y602975D02*
G03Y618285I6187J7655D01*
G01Y602975D02*
G03Y618285I6187J7655D01*
G01Y602975D02*
G03Y618285I6187J7655D01*
G01Y602975D02*
G03Y618285I6187J7655D01*
G01X7595Y602975D02*
G03Y618285I6186J7655D01*
G01X-7874Y626378D02*
G03Y634252I0J3937D01*
G01Y626378D02*
G03Y634252I0J3937D01*
G01X22835D02*
G03Y626378I0J-3937D01*
G01Y634252D02*
X137795D01*
G01X22835D02*
X137795D01*
G01X22835D02*
G03Y626378I0J-3937D01*
G01X168504Y-23622D02*
G03Y-31496I0J-3937D01*
G01X137795D02*
G03Y-23622I0J3937D01*
G01X341732Y-31496D02*
X168504D01*
G01X341732D02*
X168504D01*
G01X137795D02*
G03Y-23622I0J3937D01*
G01X168504D02*
G03Y-31496I0J-3937D01*
G01Y634252D02*
G03Y626378I0J-3937D01*
G01X137795D02*
G03Y634252I0J3937D01*
G01X168504D02*
X341732D01*
G01X168504D02*
X341732D01*
G01X137795Y626378D02*
G03Y634252I0J3937D01*
G01X168504D02*
G03Y626378I0J-3937D01*
G01X341732Y-31496D02*
G03Y-23622I0J3937D01*
G01Y-31496D02*
G03Y-23622I0J3937D01*
G01Y626378D02*
G03Y634252I0J3937D01*
G01Y626378D02*
G03Y634252I0J3937D01*
G01X372441Y-23622D02*
G03Y-31496I0J-3937D01*
G01X529921D02*
X372441D01*
G01X529921D02*
X372441D01*
G01Y-23622D02*
G03Y-31496I0J-3937D01*
G01Y634252D02*
G03Y626378I0J-3937D01*
G01Y634252D02*
X529921D01*
G01X372441D02*
X529921D01*
G01X372441D02*
G03Y626378I0J-3937D01*
G01X529921Y-31496D02*
G03Y-23622I0J3937D01*
G01Y-31496D02*
G03Y-23622I0J3937D01*
G01Y626378D02*
G03Y634252I0J3937D01*
G01Y626378D02*
G03Y634252I0J3937D01*
G01X560630Y-23622D02*
G03Y-31496I0J-3937D01*
G01X788976D02*
X560630D01*
G01X788976D02*
X560630D01*
G01Y-23622D02*
G03Y-31496I0J-3937D01*
G01Y634252D02*
G03Y626378I0J-3937D01*
G01Y634252D02*
X788976D01*
G01X560630D02*
X788976D01*
G01X560630D02*
G03Y626378I0J-3937D01*
G01X684760Y-15529D02*
G03Y-219I6187J7655D01*
G01X684759Y-15529D02*
G03X679809Y-13780I-4948J-6125D01*
G01X679811Y-1969D02*
G03X684760Y-219I0J7874D01*
G01X677165Y-1969D02*
X679811D01*
G01X677165D02*
G03Y-13780I0J-5906D01*
G01D02*
X679809D01*
G01X684760Y602975D02*
G03Y618285I6187J7655D01*
G01X684759Y602975D02*
G03Y618285I6186J7655D01*
G01Y602975D02*
G03Y618285I6186J7655D01*
G01Y602975D02*
G03Y618285I6186J7655D01*
G01Y602975D02*
G03Y618285I6186J7655D01*
G01X684760Y602975D02*
G03Y618285I6187J7655D01*
G01X679811Y616535D02*
G03X684760Y618285I0J7874D01*
G01X679809Y616535D02*
G03X684759Y618285I0J7874D01*
G01X679809Y616535D02*
G03X684759Y618285I0J7874D01*
G01X684760Y602975D02*
G03X679811Y604724I-4948J-6125D01*
G01X684759Y602975D02*
G03X679809Y604724I-4948J-6125D01*
G01X684759Y602975D02*
G03X679809Y604724I-4948J-6125D01*
G01X684759Y602975D02*
G03X679809Y604724I-4948J-6125D01*
G01X684759Y602975D02*
G03X679809Y604724I-4948J-6125D01*
G01X684760Y602975D02*
G03X679811Y604724I-4948J-6125D01*
G01X679809Y616535D02*
G03X684759Y618285I0J7874D01*
G01X679809Y616535D02*
G03X684759Y618285I0J7874D01*
G01X679811Y616535D02*
G03X684760Y618285I0J7874D01*
G01X677165Y616535D02*
X679811D01*
G01X677165D02*
G03Y604724I0J-5905D01*
G01D02*
X679809D01*
G01X788976Y-31496D02*
G03Y-23622I0J3937D01*
G01Y-31496D02*
G03Y-23622I0J3937D01*
G01X819685D02*
G03Y-31496I0J-3937D01*
G01X975591D02*
X819685D01*
G01X975591D02*
X819685D01*
G01Y-23622D02*
G03Y-31496I0J-3937D01*
G01X788976Y626378D02*
G03Y634252I0J3937D01*
G01Y626378D02*
G03Y634252I0J3937D01*
G01X819685D02*
G03Y626378I0J-3937D01*
G01Y634252D02*
X975591D01*
G01X819685D02*
X975591D01*
G01X819685D02*
G03Y626378I0J-3937D01*
G01X975591Y-31496D02*
G03Y-23622I0J3937D01*
G01Y-31496D02*
G03Y-23622I0J3937D01*
G01X1006299D02*
G03Y-31496I0J-3937D01*
G01X1162205D02*
X1006299D01*
G01X1162205D02*
X1006299D01*
G01Y-23622D02*
G03Y-31496I0J-3937D01*
G01Y634252D02*
X1162205D01*
G01X1006299D02*
X1162205D01*
G01X975591Y626378D02*
G03Y634252I0J3937D01*
G01Y626378D02*
G03Y634252I0J3937D01*
G01X1006299D02*
G03Y626378I0J-3937D01*
G01Y634252D02*
G03Y626378I0J-3937D01*
G01X1162205Y-31496D02*
G03Y-23622I0J3937D01*
G01Y-31496D02*
G03Y-23622I0J3937D01*
G01X1192913D02*
G03Y-31496I0J-3937D01*
G01X1398425D02*
X1192913D01*
G01X1398425D02*
X1192913D01*
G01Y-23622D02*
G03Y-31496I0J-3937D01*
G01Y634252D02*
X1394488D01*
G01X1192913D02*
X1394488D01*
G01X1162205Y626378D02*
G03Y634252I0J3937D01*
G01Y626378D02*
G03Y634252I0J3937D01*
G01X1192913D02*
G03Y626378I0J-3937D01*
G01Y634252D02*
G03Y626378I0J-3937D01*
G01X1398425Y-31496D02*
G03Y-23622I0J3937D01*
G01Y-31496D02*
G03Y-23622I0J3937D01*
G01X1405512Y-1968D02*
G03Y-13779I0J-5906D01*
G01Y-1968D02*
G03Y-13779I0J-5906D01*
G01Y-1968D02*
G03Y-13779I0J-5906D01*
G01Y-1968D02*
G03Y-13779I0J-5906D01*
G01X1394488Y626378D02*
G03Y634252I0J3937D01*
G01Y626378D02*
G03Y634252I0J3937D01*
G01X1405512Y616535D02*
G03Y604724I0J-5905D01*
G01Y616535D02*
G03Y604724I0J-5905D01*
G01Y616535D02*
G03Y604724I0J-5905D01*
G01Y616535D02*
G03Y604724I0J-5905D01*
G01X1429134Y-23622D02*
G03Y-31496I0J-3937D01*
G01X1851181D02*
X1429134D01*
G01X1851181D02*
X1429134D01*
G01Y-23622D02*
G03Y-31496I0J-3937D01*
G01X1413107Y-15529D02*
G03Y-218I6186J7655D01*
G01X1413105Y-15529D02*
G03Y-218I6186J7655D01*
G01Y-15529D02*
G03Y-218I6186J7655D01*
G01Y-15529D02*
G03Y-218I6186J7655D01*
G01Y-15529D02*
G03Y-218I6186J7655D01*
G01X1413107Y-15529D02*
G03Y-218I6186J7655D01*
G01X1408157Y-1968D02*
G03X1413107Y-218I1J7874D01*
G01X1408156Y-1968D02*
G03X1413105Y-218I0J7874D01*
G01X1408156Y-1968D02*
G03X1413105Y-218I0J7874D01*
G01X1408156Y-1968D02*
G03X1413105Y-218I0J7874D01*
G01X1408156Y-1968D02*
G03X1413105Y-218I0J7874D01*
G01X1408157Y-1968D02*
G03X1413107Y-218I1J7874D01*
G01Y-15529D02*
G03X1408157Y-13779I-4949J-6124D01*
G01X1413105Y-15529D02*
G03X1408156Y-13779I-4949J-6124D01*
G01X1413105Y-15529D02*
G03X1408156Y-13779I-4949J-6124D01*
G01X1413105Y-15529D02*
G03X1408156Y-13779I-4949J-6124D01*
G01X1413105Y-15529D02*
G03X1408156Y-13779I-4949J-6124D01*
G01X1413107Y-15529D02*
G03X1408157Y-13779I-4949J-6124D01*
G01X1405512D02*
X1408156D01*
G01X1408157D02*
X1405512D01*
G01X1408157D02*
X1405512D01*
G01D02*
X1408156D01*
G01X1405512Y-1968D02*
X1408157D01*
G01X1408156D02*
X1405512D01*
G01X1408156D02*
X1405512D01*
G01D02*
X1408157D01*
G01X1425197Y634252D02*
X1851181D01*
G01X1425197D02*
X1851181D01*
G01X1425197D02*
G03Y626378I0J-3937D01*
G01Y634252D02*
G03Y626378I0J-3937D01*
G01X1408157Y616535D02*
G03X1413107Y618285I1J7874D01*
G01X1408156Y616535D02*
G03X1413105Y618285I0J7874D01*
G01X1408156Y616535D02*
G03X1413105Y618285I0J7874D01*
G01X1413107Y602975D02*
G03Y618285I6186J7655D01*
G01X1413105Y602975D02*
G03Y618285I6187J7655D01*
G01Y602975D02*
G03Y618285I6187J7655D01*
G01X1413107Y602975D02*
G03X1408157Y604724I-4948J-6125D01*
G01X1413105Y602975D02*
G03X1408156Y604724I-4948J-6125D01*
G01X1413105Y602975D02*
G03X1408156Y604724I-4948J-6125D01*
G01X1413105Y602975D02*
G03X1408156Y604724I-4948J-6125D01*
G01X1413105Y602975D02*
G03X1408156Y604724I-4948J-6125D01*
G01X1413107Y602975D02*
G03X1408157Y604724I-4948J-6125D01*
G01X1413105Y602975D02*
G03Y618285I6187J7655D01*
G01Y602975D02*
G03Y618285I6187J7655D01*
G01X1413107Y602975D02*
G03Y618285I6186J7655D01*
G01X1408156Y616535D02*
G03X1413105Y618285I0J7874D01*
G01X1408156Y616535D02*
G03X1413105Y618285I0J7874D01*
G01X1408157Y616535D02*
G03X1413107Y618285I1J7874D01*
G01X1405512Y616535D02*
X1408157D01*
G01X1408156D02*
X1405512D01*
G01Y604724D02*
X1408156D01*
G01X1408157D02*
X1405512D01*
G01X1408157D02*
X1405512D01*
G01D02*
X1408156D01*
G01Y616535D02*
X1405512D01*
G01D02*
X1408157D01*
G01X1685866Y267244D02*
X1883780D01*
G01X1685866D02*
X1883780D01*
G01X1685866D02*
X1883780D01*
G01X1685866D02*
X1883780D01*
G01X1681929Y271181D02*
G03X1685866Y267244I3937J0D01*
G01X1681929Y271181D02*
G03X1685866Y267244I3937J0D01*
G01X1681929Y271181D02*
G03X1685866Y267244I3937J0D01*
G01X1681929Y271181D02*
G03X1685866Y267244I3937J0D01*
G01X1681929Y428661D02*
Y271181D01*
G01Y428661D02*
Y271181D01*
G01Y428661D02*
Y271181D01*
G01Y428661D02*
Y271181D01*
G01X1685866Y432598D02*
G03X1681929Y428661I0J-3937D01*
G01X1685866Y432598D02*
G03X1681929Y428661I0J-3937D01*
G01X1972441Y432598D02*
X1685866D01*
G01X1972441D02*
X1685866D01*
G01X1972441D02*
X1685866D01*
G01X1972441D02*
X1685866D01*
G01D02*
G03X1681929Y428661I0J-3937D01*
G01X1685866Y432598D02*
G03X1681929Y428661I0J-3937D01*
G01X1851181Y-31496D02*
G03Y-23622I0J3937D01*
G01Y-31496D02*
G03Y-23622I0J3937D01*
G01X1881890D02*
G03Y-31496I0J-3937D01*
G01X1972441D02*
X1881890D01*
G01X1972441D02*
X1881890D01*
G01Y-23622D02*
G03Y-31496I0J-3937D01*
G01X1861926Y-15529D02*
G03X1856976Y-13780I-4948J-6125D01*
G01X1861924Y-15529D02*
G03X1856975Y-13780I-4948J-6125D01*
G01X1861924Y-15529D02*
G03X1856975Y-13780I-4948J-6125D01*
G01X1861924Y-15529D02*
G03X1856975Y-13780I-4948J-6125D01*
G01X1861924Y-15529D02*
G03X1856975Y-13780I-4948J-6125D01*
G01X1861926Y-15529D02*
G03X1856976Y-13780I-4948J-6125D01*
G01Y-1969D02*
G03X1861926Y-219I0J7874D01*
G01X1856975Y-1969D02*
G03X1861924Y-219I0J7874D01*
G01X1856975Y-1969D02*
G03X1861924Y-219I0J7874D01*
G01X1861926Y-15529D02*
G03Y-219I6186J7655D01*
G01X1861924Y-15529D02*
G03Y-219I6186J7655D01*
G01Y-15529D02*
G03Y-219I6186J7655D01*
G01Y-15529D02*
G03Y-219I6186J7655D01*
G01Y-15529D02*
G03Y-219I6186J7655D01*
G01X1861926Y-15529D02*
G03Y-219I6186J7655D01*
G01X1856975Y-1969D02*
G03X1861924Y-219I0J7874D01*
G01X1856975Y-1969D02*
G03X1861924Y-219I0J7874D01*
G01X1856976Y-1969D02*
G03X1861926Y-219I0J7874D01*
G01X1854331Y-1969D02*
G03Y-13780I0J-5906D01*
G01Y-1969D02*
G03Y-13780I0J-5906D01*
G01D02*
X1856975D01*
G01X1856976D02*
X1854331D01*
G01X1856976D02*
X1854331D01*
G01D02*
X1856975D01*
G01X1854331Y-1969D02*
G03Y-13780I0J-5906D01*
G01Y-1969D02*
G03Y-13780I0J-5906D01*
G01Y-1969D02*
X1856976D01*
G01X1856975D02*
X1854331D01*
G01X1856975D02*
X1854331D01*
G01D02*
X1856976D01*
G01X1891654Y246772D02*
X1972441D01*
G01X1891654D02*
X1972441D01*
G01X1891654D02*
X1972441D01*
G01X1891654D02*
X1972441D01*
G01X1887717Y250709D02*
G03X1891654Y246772I3937J0D01*
G01X1887717Y250709D02*
G03X1891654Y246772I3937J0D01*
G01X1887717Y263307D02*
Y250709D01*
G01Y263307D02*
Y250709D01*
G01Y263307D02*
Y250709D01*
G01Y263307D02*
Y250709D01*
G01D02*
G03X1891654Y246772I3937J0D01*
G01X1887717Y250709D02*
G03X1891654Y246772I3937J0D01*
G01X1887717Y263307D02*
G03X1883780Y267244I-3937J0D01*
G01X1887717Y263307D02*
G03X1883780Y267244I-3937J0D01*
G01X1887717Y263307D02*
G03X1883780Y267244I-3937J0D01*
G01X1887717Y263307D02*
G03X1883780Y267244I-3937J0D01*
G01X1881890Y634252D02*
G03Y626378I0J-3937D01*
G01Y634252D02*
X1972441D01*
G01X1881890D02*
X1972441D01*
G01X1881890D02*
G03Y626378I0J-3937D01*
G01X1851181D02*
G03Y634252I0J3937D01*
G01Y626378D02*
G03Y634252I0J3937D01*
G01X1856976Y616535D02*
G03X1861926Y618285I0J7874D01*
G01X1856975Y616535D02*
G03X1861924Y618285I0J7874D01*
G01X1856975Y616535D02*
G03X1861924Y618285I0J7874D01*
G01X1861926Y602975D02*
G03Y618285I6186J7655D01*
G01X1861924Y602975D02*
G03Y618285I6186J7655D01*
G01Y602975D02*
G03Y618285I6186J7655D01*
G01Y602975D02*
G03Y618285I6186J7655D01*
G01Y602975D02*
G03Y618285I6186J7655D01*
G01X1861926Y602975D02*
G03Y618285I6186J7655D01*
G01X1856975Y616535D02*
G03X1861924Y618285I0J7874D01*
G01X1856975Y616535D02*
G03X1861924Y618285I0J7874D01*
G01X1856976Y616535D02*
G03X1861926Y618285I0J7874D01*
G01Y602975D02*
G03X1856976Y604724I-4948J-6125D01*
G01X1861924Y602975D02*
G03X1856975Y604724I-4948J-6125D01*
G01X1861924Y602975D02*
G03X1856975Y604724I-4948J-6125D01*
G01X1861924Y602975D02*
G03X1856975Y604724I-4948J-6125D01*
G01X1861924Y602975D02*
G03X1856975Y604724I-4948J-6125D01*
G01X1861926Y602975D02*
G03X1856976Y604724I-4948J-6125D01*
G01X1854331Y616535D02*
G03Y604724I0J-5905D01*
G01Y616535D02*
G03Y604724I0J-5905D01*
G01D02*
X1856975D01*
G01X1856976D02*
X1854331D01*
G01X1856976D02*
X1854331D01*
G01D02*
X1856975D01*
G01X1854331Y616535D02*
G03Y604724I0J-5905D01*
G01Y616535D02*
G03Y604724I0J-5905D01*
G01Y616535D02*
X1856976D01*
G01X1856975D02*
X1854331D01*
G01X1856975D02*
X1854331D01*
G01D02*
X1856976D01*
G01X1972441Y-11811D02*
X1906890D01*
G01X1904921Y-9843D02*
G03X1906890Y-11811I1969J1D01*
G01X1904921Y53150D02*
Y-9843D01*
G01X1972441Y-11811D02*
X1906890D01*
G01X1904921Y-9843D02*
G03X1906890Y-11811I1969J1D01*
G01X1904921Y53150D02*
Y-9843D01*
G01X1923071Y53150D02*
Y-9843D01*
G01X1940787Y-3937D02*
X1972441D01*
G01X1940787D02*
G03X1938819Y-5906I0J-1968D01*
G01Y-9843D02*
Y-5906D01*
G01Y-9843D02*
G03X1940787Y-11811I1968J0D01*
G01X1921102D02*
G03X1923071Y-9843I0J1969D01*
G01X1906890Y55118D02*
G03X1904921Y53150I0J-1969D01*
G01X1972441Y55118D02*
X1906890D01*
G01X1972441D02*
X1906890D01*
G01X1972441D02*
X1906890D01*
G01X1972441D02*
X1906890D01*
G01D02*
G03X1904921Y53150I0J-1969D01*
G01X1923071D02*
G03X1921102Y55118I-1969J-1D01*
G01X1940787D02*
G03X1938819Y53150I0J-1968D01*
G01Y49213D02*
Y53150D01*
G01Y49213D02*
G03X1940787Y47244I1968J-1D01*
G01X1972441D02*
X1940787D01*
G01X1976378Y-35433D02*
G03X1972441Y-31496I-3937J0D01*
G01X1976378Y-59055D02*
Y-35433D01*
G01Y-59055D02*
Y-35433D01*
G01D02*
G03X1972441Y-31496I-3937J0D01*
G01Y-62992D02*
G03X1976378Y-59055I0J3937D01*
G01X1972441Y-62992D02*
G03X1976378Y-59055I0J3937D01*
G01X1972441Y-23622D02*
G03X1976378Y-19685I0J3937D01*
G01X1972441Y-23622D02*
G03X1976378Y-19685I0J3937D01*
G01X1972441Y-23622D02*
G03X1976378Y-19685I0J3937D01*
G01X1972441Y-23622D02*
G03X1976378Y-19685I0J3937D01*
G01D02*
Y-15748D01*
G01Y-19685D02*
Y-15748D01*
G01Y-19685D02*
Y-15748D01*
G01Y-19685D02*
Y-15748D01*
G01D02*
G03X1972441Y-11811I-3937J0D01*
G01X1976378Y-15748D02*
G03X1972441Y-11811I-3937J0D01*
G01X1976378Y-15748D02*
G03X1972441Y-11811I-3937J0D01*
G01X1976378Y-15748D02*
G03X1972441Y-11811I-3937J0D01*
G01X1976378Y0D02*
Y43307D01*
G01X1972441Y-3937D02*
G03X1976378Y0I0J3937D01*
G01X1972441Y55118D02*
G03X1976378Y59055I0J3937D01*
G01X1972441Y55118D02*
G03X1976378Y59055I0J3937D01*
G01X1972441Y55118D02*
G03X1976378Y59055I0J3937D01*
G01X1972441Y55118D02*
G03X1976378Y59055I0J3937D01*
G01D02*
Y242835D01*
G01Y59055D02*
Y242835D01*
G01Y59055D02*
Y242835D01*
G01Y59055D02*
Y242835D01*
G01Y43307D02*
G03X1972441Y47244I-3937J0D01*
G01X1976378Y242835D02*
G03X1972441Y246772I-3937J0D01*
G01X1976378Y242835D02*
G03X1972441Y246772I-3937J0D01*
G01X1976378Y242835D02*
G03X1972441Y246772I-3937J0D01*
G01X1976378Y242835D02*
G03X1972441Y246772I-3937J0D01*
G01Y432598D02*
G03X1976378Y436535I0J3937D01*
G01X1972441Y432598D02*
G03X1976378Y436535I0J3937D01*
G01X1972441Y432598D02*
G03X1976378Y436535I0J3937D01*
G01X1972441Y432598D02*
G03X1976378Y436535I0J3937D01*
G01D02*
Y622441D01*
G01Y436535D02*
Y622441D01*
G01Y436535D02*
Y622441D01*
G01Y436535D02*
Y622441D01*
G01D02*
G03X1972441Y626378I-3937J0D01*
G01X1976378Y622441D02*
G03X1972441Y626378I-3937J0D01*
G01X1976378Y622441D02*
G03X1972441Y626378I-3937J0D01*
G01X1976378Y622441D02*
G03X1972441Y626378I-3937J0D01*
G01Y634252D02*
G03X1976378Y638189I0J3937D01*
G01X1972441Y634252D02*
G03X1976378Y638189I0J3937D01*
G01D02*
Y661811D01*
G01Y638189D02*
Y661811D01*
G01D02*
G03X1972441Y665748I-3937J0D01*
G01X1976378Y661811D02*
G03X1972441Y665748I-3937J0D01*
G54D28*
X44100Y507100D03*
X1468500Y176700D03*
X1596130Y205480D03*
X1623800Y169500D03*
X1666300Y85000D03*
X1742200Y87950D03*
X1755708Y132250D03*
Y127750D03*
Y141250D03*
Y136750D03*
X1764270Y132250D03*
Y127750D03*
Y141250D03*
Y136750D03*
X1755708Y145798D03*
X1764222D03*
X1721900Y198700D03*
X1888500Y225100D03*
G54D139*
X1681717Y116349D03*
G54D64*
X594800Y366894D03*
G54D91*
X1296679Y228017D03*
X1289679Y222899D03*
X1296679Y225458D03*
X1289679Y228017D03*
X1296679Y222899D03*
X1460354Y148569D03*
Y146010D03*
Y151128D03*
X1524200Y12218D03*
Y7100D03*
X1510200Y9641D03*
Y12200D03*
Y7082D03*
X1517200D03*
Y9641D03*
Y12200D03*
X1480354Y151039D03*
Y148479D03*
X1473354Y151039D03*
Y145919D03*
Y148479D03*
X1480354Y145919D03*
X1467354Y151128D03*
Y146010D03*
X1528065Y171552D03*
Y174112D03*
Y176672D03*
X1506000Y186570D03*
Y184010D03*
X1499000Y186570D03*
Y181450D03*
Y184010D03*
X1506000Y181450D03*
X1488962Y190185D03*
X1481962Y187626D03*
Y185067D03*
X1488962D03*
X1481962Y190185D03*
X1531200Y7100D03*
Y9659D03*
Y12218D03*
X1535065Y171552D03*
Y176672D03*
Y174112D03*
X1548628Y176772D03*
Y174212D03*
X1541628Y176772D03*
Y171652D03*
Y174212D03*
X1548628Y171652D03*
X1547650Y258590D03*
X1540650Y256031D03*
Y253472D03*
X1547650D03*
X1540650Y258590D03*
X1544300Y248318D03*
X1537300Y245759D03*
Y243200D03*
X1544300D03*
X1537300Y248318D03*
X1594600Y-14300D03*
X1601600Y-11741D03*
X1594600Y-9182D03*
X1601600Y-14300D03*
Y-9182D03*
X1613000Y-6218D03*
X1620000Y-3659D03*
X1613000Y-1100D03*
X1620000Y-6218D03*
Y-1100D03*
X1648296Y301559D03*
X1641296Y296441D03*
Y299000D03*
X1648296Y296441D03*
X1641296Y301559D03*
X1620717Y370711D03*
Y368151D03*
X1613717Y370711D03*
Y365591D03*
Y368151D03*
X1620717Y365591D03*
Y349711D03*
Y347151D03*
X1613717Y349711D03*
Y344591D03*
Y347151D03*
X1620717Y344591D03*
Y360211D03*
Y357651D03*
X1613717Y360211D03*
Y355091D03*
Y357651D03*
X1620717Y355091D03*
X1662526Y300586D03*
X1655526Y298027D03*
X1662526Y295468D03*
X1655526Y300586D03*
Y295468D03*
X1759900Y509359D03*
Y506800D03*
X1752900Y509359D03*
Y506800D03*
Y511918D03*
X1759900D03*
X1757792Y581471D03*
X1750792Y578912D03*
X1757792Y576353D03*
X1750792Y581471D03*
Y576353D03*
X1761300Y613600D03*
Y618718D03*
X1754300D03*
Y616159D03*
Y613600D03*
X1735000Y618700D03*
Y613582D03*
X1742000D03*
Y616141D03*
Y618700D03*
X1808400Y557982D03*
X1815400Y560541D03*
X1808400Y563100D03*
X1815400Y557982D03*
Y563100D03*
X1872115Y586119D03*
X1879115D03*
X1872115Y588679D03*
X1879115Y591239D03*
Y588679D03*
X1872115Y591239D03*
G54D157*
X1871988Y55350D03*
X1875924D03*
Y47250D03*
X1871988D03*
X1873956Y55350D03*
X1877892D03*
X1873956Y47250D03*
X1877892D03*
G54D148*
X1762519Y560809D03*
Y566793D03*
X1816154Y532970D03*
Y538954D03*
G54D166*
X1906500Y214650D03*
Y223650D03*
G54D46*
X83939Y320948D03*
X69200Y364500D03*
X114158Y122310D03*
X1613200Y82000D03*
X1744500Y61300D03*
X1776750Y567650D03*
Y571695D03*
X1886466Y473995D03*
G54D82*
X1236921Y337307D03*
G54D19*
X23940Y24559D03*
X20320Y53240D03*
X10440Y564000D03*
X12130Y529080D03*
X134164Y209283D03*
X134374Y241333D03*
X133850Y273300D03*
X134174Y305323D03*
Y337533D03*
X134434Y369363D03*
X783752Y209163D03*
X783782Y241283D03*
Y273533D03*
X784492Y305563D03*
X784322Y337353D03*
X783712Y369433D03*
G54D37*
X67500Y276800D03*
X84522Y389977D03*
X90811Y444806D03*
X100287Y426488D03*
X97916Y436463D03*
X82464Y407622D03*
X81387Y434036D03*
X103799Y431342D03*
X91900Y429101D03*
X599199Y240594D03*
X1077942Y112727D03*
X1378550Y344550D03*
X1450413Y246661D03*
X1565671Y534929D03*
X1576454Y547056D03*
X1624547Y123148D03*
X1624064Y174709D03*
G54D73*
X634044Y184570D03*
G54D55*
X388187Y13078D03*
Y50878D03*
Y88678D03*
Y514079D03*
Y589679D03*
Y551879D03*
X1037797Y13078D03*
Y88678D03*
Y50878D03*
Y514079D03*
Y589679D03*
Y551879D03*
G54D56*
X503389Y136125D03*
G54D65*
X586109Y367405D03*
G54D149*
X1760354Y569942D03*
X1758386D03*
X1756417D03*
X1754448D03*
X1752480D03*
X1810052Y542103D03*
X1813989D03*
X1812021D03*
X1808083D03*
X1806115D03*
G54D158*
X1866730Y509560D03*
Y527560D03*
X1871850Y509560D03*
Y527560D03*
X1869290Y509560D03*
Y527560D03*
X1874410Y509560D03*
Y527560D03*
G54D29*
X40200Y495721D03*
Y487879D03*
X36458D03*
X43942D03*
Y495721D03*
X36458D03*
G54D38*
X61200Y274300D03*
X1339862Y256652D03*
X1397910Y248590D03*
X1389637Y258137D03*
X1346683Y251175D03*
X1353668Y255112D03*
X1368828Y247672D03*
X1382472Y256172D03*
X1346640Y260796D03*
X1362848Y252308D03*
X1387012Y250288D03*
X1528368Y508532D03*
X1583861Y67690D03*
X1597307Y114193D03*
X1750253Y135786D03*
X1716228Y154772D03*
G54D92*
X1319247Y266720D03*
X1324460Y260962D03*
X1329815Y255507D03*
X1318297Y255241D03*
X1323510Y272768D03*
X1328865Y266711D03*
X1500000Y353010D03*
X1590293Y51938D03*
X1626600Y356893D03*
X1729189Y150153D03*
X1740889Y151176D03*
X1751189Y123542D03*
X1959200Y574929D03*
G54D167*
X1931994Y212699D03*
X1928449Y226251D03*
G54D83*
X1250110Y336170D03*
G54D74*
X638108Y385368D03*
G54D47*
X94000Y310400D03*
X882380Y355289D03*
X1470500Y163700D03*
X1476800Y234017D03*
X1484890Y268660D03*
X1478400Y267500D03*
X1528400Y502500D03*
X1936170Y233087D03*
X1935220Y226688D03*
G54D66*
X584181Y360208D03*
G54D57*
X594741Y135085D03*
G54D93*
X1371834Y263088D03*
X1366331Y258929D03*
X1476265Y437109D03*
G54D39*
X94500Y299000D03*
X89000D03*
X353500Y13200D03*
X348000D03*
X324642D03*
X330142D03*
X312342D03*
X317842D03*
X337642D03*
X343142D03*
X353500Y51000D03*
X348000D03*
X312342D03*
X317842D03*
X324642D03*
X330142D03*
X337642D03*
X343142D03*
X353500Y552000D03*
X348000D03*
X312342D03*
X317842D03*
X324642D03*
X330142D03*
X337642D03*
X343142D03*
X353500Y589800D03*
X348000D03*
X312342D03*
X317842D03*
X324642D03*
X330142D03*
X337642D03*
X343142D03*
X417150Y13200D03*
X411650D03*
X361042Y13078D03*
X366542D03*
X404700Y13200D03*
X399200D03*
X417150Y51000D03*
X411650D03*
X361058Y50742D03*
X366558D03*
X404700Y51000D03*
X399200D03*
X417150Y552000D03*
X411650D03*
X360870Y551820D03*
X366370D03*
X404700Y552000D03*
X399200D03*
X417150Y589800D03*
X411650D03*
X360090Y589680D03*
X365590D03*
X404700Y589800D03*
X399200D03*
X430150Y13200D03*
X424650D03*
X442508D03*
X437008D03*
X442508Y51000D03*
X437008D03*
X430150D03*
X424650D03*
X430150Y552000D03*
X424650D03*
X442508D03*
X437008D03*
X430150Y589800D03*
X424650D03*
X442508D03*
X437008D03*
X600000Y-6700D03*
X599000Y32000D03*
Y70000D03*
X600892Y532978D03*
Y570778D03*
X599992Y609378D03*
X616500Y32000D03*
X611000D03*
X616500Y-6700D03*
X611000D03*
X605500D03*
X604500Y32000D03*
X616500Y70000D03*
X611000D03*
X604500D03*
X616892Y570778D03*
X611392D03*
X616892Y532978D03*
X611392D03*
X606392D03*
Y570778D03*
X615992Y609378D03*
X610492D03*
X605492D03*
X671000Y13600D03*
X665500D03*
X677550Y21856D03*
X683050D03*
X671000Y18500D03*
X665500D03*
X670569Y577612D03*
X665069D03*
X961950Y13200D03*
X967450D03*
X961850Y51000D03*
X967350D03*
X961950Y552000D03*
X967450D03*
X961950Y589800D03*
X967450D03*
X1010900Y13078D03*
X1016400D03*
X1003108Y13200D03*
X997608D03*
X987250D03*
X992750D03*
X974250D03*
X979750D03*
X1003108Y51000D03*
X997608D03*
X1010800Y50500D03*
X1016300D03*
X974250Y51000D03*
X979750D03*
X987250D03*
X992750D03*
X1003108Y552000D03*
X997608D03*
X1011100Y551900D03*
X1016600D03*
X974250Y552000D03*
X979750D03*
X987250D03*
X992750D03*
X1009800Y589700D03*
X1015300D03*
X974250Y589800D03*
X979750D03*
X987250D03*
X992750D03*
X1003108D03*
X997608D03*
X1092116Y13200D03*
X1086616D03*
X1079758D03*
X1074258D03*
X1066758D03*
X1061258D03*
X1054308D03*
X1048808D03*
X1092116Y51000D03*
X1086616D03*
X1079758D03*
X1074258D03*
X1066758D03*
X1061258D03*
X1054308D03*
X1048808D03*
X1092116Y552000D03*
X1086616D03*
X1079758D03*
X1074258D03*
X1066758D03*
X1061258D03*
X1054308D03*
X1048808D03*
X1079758Y589800D03*
X1074258D03*
X1092116D03*
X1086616D03*
X1066758D03*
X1061258D03*
X1054308D03*
X1048808D03*
X1249608Y-6700D03*
X1255108D03*
X1266108D03*
X1260608D03*
X1248608Y32000D03*
X1254108D03*
X1266108D03*
X1260608D03*
X1248608Y70000D03*
X1254108D03*
X1266108D03*
X1260608D03*
X1248608Y533000D03*
X1254108D03*
X1266108D03*
X1260608D03*
X1248608Y571000D03*
X1254108D03*
X1266108D03*
X1260608D03*
X1248374Y609456D03*
X1253874D03*
X1266500Y609500D03*
X1261000D03*
X1337500Y47000D03*
X1332000D03*
X1444047Y402285D03*
X1449547D03*
X1462850Y407900D03*
X1457350D03*
X1462850Y412900D03*
X1457350D03*
X1447000Y408000D03*
X1452500D03*
X1447000Y413000D03*
X1452500D03*
X1462800Y526800D03*
X1460750Y543500D03*
X1466250D03*
X1468300Y526800D03*
X1483200Y527200D03*
X1488700D03*
X1482700Y542700D03*
X1488200D03*
X1553300Y614500D03*
X1547800D03*
X1592250Y90500D03*
X1597750D03*
X1608349Y90538D03*
X1613849D03*
X1599193Y70229D03*
X1604193D03*
X1641099Y156438D03*
X1635599D03*
X1644750Y122000D03*
X1639250D03*
X1606250Y102500D03*
X1611750D03*
X1598500Y124750D03*
X1604000D03*
X1639171Y134592D03*
X1644671D03*
X1606500Y371948D03*
X1601000D03*
X1606500Y367248D03*
X1601000D03*
X1616300Y486700D03*
X1610800D03*
X1623750Y514200D03*
X1618250D03*
X1623750Y509500D03*
X1618250D03*
X1797650Y163440D03*
X1803150D03*
X1881150Y142800D03*
X1875650D03*
X1881150Y147800D03*
X1875650D03*
X1884689Y137717D03*
X1890189D03*
X1838363Y143448D03*
X1843863D03*
X1890750Y183300D03*
X1896250D03*
X1894900Y163500D03*
X1889400D03*
X1896150Y178600D03*
X1890650D03*
X1916513Y179468D03*
X1922013D03*
X1916513Y184468D03*
X1922013D03*
X1916513Y189468D03*
X1922013D03*
X1917100Y167400D03*
X1922600D03*
G54D48*
X64500Y355700D03*
X68000D03*
X667500Y254200D03*
X1504631Y601856D03*
X1466610Y604329D03*
G54D75*
X634137Y404629D03*
G54D84*
X1224391Y365477D03*
G54D159*
X1872938Y483295D03*
Y485263D03*
Y489200D03*
Y491169D03*
X1875237Y483295D03*
Y485263D03*
Y489200D03*
Y491169D03*
X1960252Y180204D03*
Y182172D03*
Y186109D03*
Y188078D03*
X1962551Y180204D03*
Y182172D03*
Y186109D03*
Y188078D03*
G54D168*
X1928842Y222302D03*
X1930810D03*
X1934747D03*
X1936716D03*
X1928842Y220003D03*
X1930810D03*
X1934747D03*
X1936716D03*
G54D58*
X543984Y131273D03*
G54D94*
X1373950Y337213D03*
Y338788D03*
Y340363D03*
Y341938D03*
Y343513D03*
Y345087D03*
Y346662D03*
Y348237D03*
Y349812D03*
Y351387D03*
G54D76*
X671037Y176163D03*
G54D169*
X1932779Y221153D03*
G54D49*
X64500Y359300D03*
X68000D03*
X667500Y257800D03*
X1504631Y605456D03*
X1466610Y607929D03*
G54D85*
X1238475Y360530D03*
G54D67*
X600568Y359708D03*
G54D95*
X1354650Y340363D03*
Y338788D03*
Y337213D03*
Y351387D03*
Y349812D03*
Y348237D03*
Y346662D03*
Y345087D03*
Y343513D03*
Y341938D03*
G54D59*
X601995Y156616D03*
G54D77*
X671371Y193310D03*
G54D86*
X1246438Y366646D03*
G54D68*
X541260Y429470D03*
X540310Y443259D03*
G54D78*
X699050Y226500D03*
X1367239Y8476D03*
X1366860Y40490D03*
X1352457Y360095D03*
X1369307Y399408D03*
X1371060Y587276D03*
X1367450Y616400D03*
X1420000Y558398D03*
X1427901Y558435D03*
X1560929Y618572D03*
X1569307Y618555D03*
G54D96*
X1357213Y334650D03*
X1358788D03*
X1360363D03*
X1361938D03*
X1363513D03*
X1365087D03*
X1366662D03*
X1368237D03*
X1369812D03*
X1371387D03*
G54D69*
X632584Y147965D03*
G54D87*
X1228715Y362963D03*
G54D79*
X695450Y226500D03*
X1363639Y8476D03*
X1363260Y40490D03*
X1348857Y360095D03*
X1365707Y399408D03*
X1367460Y587276D03*
X1363850Y616400D03*
X1416400Y558398D03*
X1424301Y558435D03*
X1557329Y618572D03*
X1565707Y618555D03*
G54D97*
X1371387Y353950D03*
X1369812D03*
X1368237D03*
X1366662D03*
X1365087D03*
X1363513D03*
X1361938D03*
X1360363D03*
X1358788D03*
X1357213D03*
G54D88*
X1233239Y366212D03*
G54D98*
X1402430Y483176D03*
G54D89*
X1242459Y344788D03*
G54D99*
X1415400Y23730D03*
X1421400Y16700D03*
X1420337Y48377D03*
X1414091Y46412D03*
X1473886Y35185D03*
X1569553Y32168D03*
X1583256Y29400D03*
X1581000Y465400D03*
M02*
